(kicad_sch (version 20211123) (generator eeschema)

  (paper "A3")

  (title_block
    (title "SA800U (Snapdragon 845) Baseboard")
    (date "2023-10-19")
    (rev "1.0.3")
    (company "Antmicro Ltd.")
    (comment 1 "www.antmicro.com")
  )

  (junction (at 203.581 183.896) (diameter 0) (color 0 0 0 0)
  )
  (junction (at 259.715 128.27) (diameter 0) (color 0 0 0 0)
  )
  (junction (at 247.65 186.436) (diameter 0) (color 0 0 0 0)
  )
  (junction (at 241.681 197.866) (diameter 0) (color 0 0 0 0)
  )
  (junction (at 205.74 140.97) (diameter 0) (color 0 0 0 0)
  )
  (junction (at 157.861 186.436) (diameter 0) (color 0 0 0 0)
  )
  (junction (at 203.581 186.436) (diameter 0) (color 0 0 0 0)
  )
  (junction (at 219.71 128.27) (diameter 0) (color 0 0 0 0)
  )
  (junction (at 267.97 55.245) (diameter 0) (color 0 0 0 0)
  )
  (junction (at 241.681 195.326) (diameter 0) (color 0 0 0 0)
  )
  (junction (at 271.78 181.356) (diameter 0) (color 0 0 0 0)
  )
  (junction (at 219.71 140.97) (diameter 0) (color 0 0 0 0)
  )
  (junction (at 180.594 168.656) (diameter 0) (color 0 0 0 0)
  )
  (junction (at 162.941 183.896) (diameter 0) (color 0 0 0 0)
  )
  (junction (at 248.92 128.27) (diameter 0) (color 0 0 0 0)
  )
  (junction (at 224.79 140.97) (diameter 0) (color 0 0 0 0)
  )
  (junction (at 276.86 149.987) (diameter 0) (color 0 0 0 0)
  )
  (junction (at 198.247 194.056) (diameter 0) (color 0 0 0 0)
  )
  (junction (at 307.34 128.27) (diameter 0) (color 0 0 0 0)
  )
  (junction (at 259.715 68.58) (diameter 0) (color 0 0 0 0)
  )
  (junction (at 251.46 66.04) (diameter 0) (color 0 0 0 0)
  )
  (junction (at 251.46 55.245) (diameter 0) (color 0 0 0 0)
  )
  (junction (at 205.74 128.27) (diameter 0) (color 0 0 0 0)
  )
  (junction (at 281.94 176.276) (diameter 0) (color 0 0 0 0)
  )
  (junction (at 259.715 183.896) (diameter 0) (color 0 0 0 0)
  )
  (junction (at 276.225 73.66) (diameter 0) (color 0 0 0 0)
  )
  (junction (at 267.97 71.12) (diameter 0) (color 0 0 0 0)
  )
  (junction (at 178.816 194.056) (diameter 0) (color 0 0 0 0)
  )
  (junction (at 182.88 128.27) (diameter 0) (color 0 0 0 0)
  )
  (junction (at 238.76 140.97) (diameter 0) (color 0 0 0 0)
  )
  (junction (at 178.816 168.656) (diameter 0) (color 0 0 0 0)
  )
  (junction (at 224.79 128.27) (diameter 0) (color 0 0 0 0)
  )
  (junction (at 287.02 128.27) (diameter 0) (color 0 0 0 0)
  )
  (junction (at 202.692 196.596) (diameter 0) (color 0 0 0 0)
  )
  (junction (at 276.86 173.736) (diameter 0) (color 0 0 0 0)
  )
  (junction (at 259.715 55.245) (diameter 0) (color 0 0 0 0)
  )

  (no_connect (at 60.96 144.78))
  (no_connect (at 60.96 147.32))
  (no_connect (at 60.96 157.48))
  (no_connect (at 83.82 157.48))
  (no_connect (at 60.96 134.62))
  (no_connect (at 83.82 144.78))
  (no_connect (at 83.82 134.62))
  (no_connect (at 60.96 154.94))
  (no_connect (at 60.96 149.86))
  (no_connect (at 60.96 137.16))
  (no_connect (at 83.82 137.16))
  (no_connect (at 83.82 142.24))
  (no_connect (at 83.82 147.32))
  (no_connect (at 83.82 154.94))

  (wire (pts (xy 287.02 151.13) (xy 287.02 128.27))
    (stroke (width 0) (type default) (color 0 0 0 0))
  )
  (wire (pts (xy 276.225 64.008) (xy 276.225 73.66))
    (stroke (width 0) (type default) (color 0 0 0 0))
  )
  (wire (pts (xy 88.9 162.56) (xy 88.9 160.02))
    (stroke (width 0) (type default) (color 0 0 0 0))
  )
  (wire (pts (xy 287.02 128.27) (xy 307.34 128.27))
    (stroke (width 0) (type default) (color 0 0 0 0))
  )
  (wire (pts (xy 229.997 66.04) (xy 251.46 66.04))
    (stroke (width 0) (type default) (color 0 0 0 0))
  )
  (wire (pts (xy 217.17 68.58) (xy 224.917 68.58))
    (stroke (width 0) (type default) (color 0 0 0 0))
  )
  (wire (pts (xy 178.816 194.056) (xy 178.816 196.596))
    (stroke (width 0) (type default) (color 0 0 0 0))
  )
  (wire (pts (xy 60.96 139.7) (xy 43.18 139.7))
    (stroke (width 0) (type default) (color 0 0 0 0))
  )
  (wire (pts (xy 240.411 186.436) (xy 247.65 186.436))
    (stroke (width 0) (type default) (color 0 0 0 0))
  )
  (wire (pts (xy 241.681 188.976) (xy 241.681 195.326))
    (stroke (width 0) (type default) (color 0 0 0 0))
  )
  (wire (pts (xy 276.225 55.245) (xy 276.225 58.928))
    (stroke (width 0) (type default) (color 0 0 0 0))
  )
  (wire (pts (xy 200.406 166.116) (xy 209.931 166.116))
    (stroke (width 0) (type default) (color 0 0 0 0))
  )
  (wire (pts (xy 200.406 163.576) (xy 209.931 163.576))
    (stroke (width 0) (type default) (color 0 0 0 0))
  )
  (wire (pts (xy 248.92 128.27) (xy 248.92 132.08))
    (stroke (width 0) (type default) (color 0 0 0 0))
  )
  (wire (pts (xy 251.46 55.245) (xy 251.46 58.928))
    (stroke (width 0) (type default) (color 0 0 0 0))
  )
  (wire (pts (xy 259.715 55.245) (xy 267.97 55.245))
    (stroke (width 0) (type default) (color 0 0 0 0))
  )
  (wire (pts (xy 200.406 161.036) (xy 209.931 161.036))
    (stroke (width 0) (type default) (color 0 0 0 0))
  )
  (wire (pts (xy 142.621 183.896) (xy 162.941 183.896))
    (stroke (width 0) (type default) (color 0 0 0 0))
  )
  (wire (pts (xy 281.94 156.337) (xy 281.94 157.353))
    (stroke (width 0) (type default) (color 0 0 0 0))
  )
  (wire (pts (xy 219.71 135.509) (xy 219.71 140.97))
    (stroke (width 0) (type default) (color 0 0 0 0))
  )
  (wire (pts (xy 276.86 149.987) (xy 275.59 149.987))
    (stroke (width 0) (type default) (color 0 0 0 0))
  )
  (wire (pts (xy 101.6 152.4) (xy 83.82 152.4))
    (stroke (width 0) (type default) (color 0 0 0 0))
  )
  (wire (pts (xy 259.715 64.008) (xy 259.715 68.58))
    (stroke (width 0) (type default) (color 0 0 0 0))
  )
  (wire (pts (xy 217.17 73.66) (xy 224.917 73.66))
    (stroke (width 0) (type default) (color 0 0 0 0))
  )
  (wire (pts (xy 241.681 197.866) (xy 241.681 201.676))
    (stroke (width 0) (type default) (color 0 0 0 0))
  )
  (wire (pts (xy 229.997 68.58) (xy 259.715 68.58))
    (stroke (width 0) (type default) (color 0 0 0 0))
  )
  (wire (pts (xy 267.97 71.12) (xy 278.13 71.12))
    (stroke (width 0) (type default) (color 0 0 0 0))
  )
  (wire (pts (xy 142.621 186.436) (xy 157.861 186.436))
    (stroke (width 0) (type default) (color 0 0 0 0))
  )
  (wire (pts (xy 246.38 128.27) (xy 248.92 128.27))
    (stroke (width 0) (type default) (color 0 0 0 0))
  )
  (wire (pts (xy 205.74 137.16) (xy 205.74 140.97))
    (stroke (width 0) (type default) (color 0 0 0 0))
  )
  (wire (pts (xy 276.86 151.257) (xy 276.86 149.987))
    (stroke (width 0) (type default) (color 0 0 0 0))
  )
  (wire (pts (xy 202.692 196.596) (xy 202.692 199.009))
    (stroke (width 0) (type default) (color 0 0 0 0))
  )
  (wire (pts (xy 178.816 168.656) (xy 178.816 172.466))
    (stroke (width 0) (type default) (color 0 0 0 0))
  )
  (wire (pts (xy 180.594 168.656) (xy 209.931 168.656))
    (stroke (width 0) (type default) (color 0 0 0 0))
  )
  (wire (pts (xy 205.74 128.27) (xy 205.74 129.54))
    (stroke (width 0) (type default) (color 0 0 0 0))
  )
  (wire (pts (xy 240.411 195.326) (xy 241.681 195.326))
    (stroke (width 0) (type default) (color 0 0 0 0))
  )
  (wire (pts (xy 259.715 55.245) (xy 259.715 58.928))
    (stroke (width 0) (type default) (color 0 0 0 0))
  )
  (wire (pts (xy 55.88 132.08) (xy 55.88 133.35))
    (stroke (width 0) (type default) (color 0 0 0 0))
  )
  (wire (pts (xy 202.692 196.596) (xy 209.931 196.596))
    (stroke (width 0) (type default) (color 0 0 0 0))
  )
  (wire (pts (xy 276.86 156.337) (xy 276.86 157.353))
    (stroke (width 0) (type default) (color 0 0 0 0))
  )
  (wire (pts (xy 162.941 183.896) (xy 203.581 183.896))
    (stroke (width 0) (type default) (color 0 0 0 0))
  )
  (wire (pts (xy 186.436 194.056) (xy 178.816 194.056))
    (stroke (width 0) (type default) (color 0 0 0 0))
  )
  (wire (pts (xy 240.411 173.736) (xy 276.86 173.736))
    (stroke (width 0) (type default) (color 0 0 0 0))
  )
  (wire (pts (xy 217.17 66.04) (xy 224.917 66.04))
    (stroke (width 0) (type default) (color 0 0 0 0))
  )
  (wire (pts (xy 43.18 152.4) (xy 60.96 152.4))
    (stroke (width 0) (type default) (color 0 0 0 0))
  )
  (wire (pts (xy 251.46 55.245) (xy 247.65 55.245))
    (stroke (width 0) (type default) (color 0 0 0 0))
  )
  (wire (pts (xy 198.247 194.056) (xy 209.931 194.056))
    (stroke (width 0) (type default) (color 0 0 0 0))
  )
  (wire (pts (xy 240.411 181.356) (xy 271.78 181.356))
    (stroke (width 0) (type default) (color 0 0 0 0))
  )
  (wire (pts (xy 240.411 197.866) (xy 241.681 197.866))
    (stroke (width 0) (type default) (color 0 0 0 0))
  )
  (wire (pts (xy 217.17 71.12) (xy 224.917 71.12))
    (stroke (width 0) (type default) (color 0 0 0 0))
  )
  (wire (pts (xy 240.411 176.276) (xy 281.94 176.276))
    (stroke (width 0) (type default) (color 0 0 0 0))
  )
  (wire (pts (xy 219.71 147.32) (xy 219.71 157.48))
    (stroke (width 0) (type default) (color 0 0 0 0))
  )
  (wire (pts (xy 240.411 166.116) (xy 249.301 166.116))
    (stroke (width 0) (type default) (color 0 0 0 0))
  )
  (wire (pts (xy 248.92 137.16) (xy 248.92 140.97))
    (stroke (width 0) (type default) (color 0 0 0 0))
  )
  (wire (pts (xy 219.71 128.27) (xy 219.71 130.429))
    (stroke (width 0) (type default) (color 0 0 0 0))
  )
  (wire (pts (xy 267.97 55.245) (xy 276.225 55.245))
    (stroke (width 0) (type default) (color 0 0 0 0))
  )
  (wire (pts (xy 101.6 139.7) (xy 83.82 139.7))
    (stroke (width 0) (type default) (color 0 0 0 0))
  )
  (wire (pts (xy 203.581 183.896) (xy 209.931 183.896))
    (stroke (width 0) (type default) (color 0 0 0 0))
  )
  (wire (pts (xy 224.79 147.32) (xy 224.79 157.48))
    (stroke (width 0) (type default) (color 0 0 0 0))
  )
  (wire (pts (xy 259.715 137.795) (xy 259.715 149.86))
    (stroke (width 0) (type default) (color 0 0 0 0))
  )
  (wire (pts (xy 288.544 173.736) (xy 276.86 173.736))
    (stroke (width 0) (type default) (color 0 0 0 0))
  )
  (wire (pts (xy 201.041 173.736) (xy 209.931 173.736))
    (stroke (width 0) (type default) (color 0 0 0 0))
  )
  (wire (pts (xy 205.74 128.27) (xy 219.71 128.27))
    (stroke (width 0) (type default) (color 0 0 0 0))
  )
  (wire (pts (xy 307.34 128.27) (xy 309.245 128.27))
    (stroke (width 0) (type default) (color 0 0 0 0))
  )
  (wire (pts (xy 203.581 188.976) (xy 209.931 188.976))
    (stroke (width 0) (type default) (color 0 0 0 0))
  )
  (wire (pts (xy 259.715 128.27) (xy 287.02 128.27))
    (stroke (width 0) (type default) (color 0 0 0 0))
  )
  (wire (pts (xy 278.003 68.58) (xy 259.715 68.58))
    (stroke (width 0) (type default) (color 0 0 0 0))
  )
  (wire (pts (xy 287.02 172.593) (xy 287.02 184.15))
    (stroke (width 0) (type default) (color 0 0 0 0))
  )
  (wire (pts (xy 287.02 156.21) (xy 287.02 157.353))
    (stroke (width 0) (type default) (color 0 0 0 0))
  )
  (wire (pts (xy 238.76 134.62) (xy 238.76 140.97))
    (stroke (width 0) (type default) (color 0 0 0 0))
  )
  (wire (pts (xy 178.816 168.656) (xy 173.736 168.656))
    (stroke (width 0) (type default) (color 0 0 0 0))
  )
  (wire (pts (xy 202.692 204.089) (xy 202.692 206.756))
    (stroke (width 0) (type default) (color 0 0 0 0))
  )
  (wire (pts (xy 281.94 172.593) (xy 281.94 176.276))
    (stroke (width 0) (type default) (color 0 0 0 0))
  )
  (wire (pts (xy 219.71 140.97) (xy 219.71 142.24))
    (stroke (width 0) (type default) (color 0 0 0 0))
  )
  (wire (pts (xy 224.79 128.27) (xy 236.22 128.27))
    (stroke (width 0) (type default) (color 0 0 0 0))
  )
  (wire (pts (xy 203.581 186.436) (xy 209.931 186.436))
    (stroke (width 0) (type default) (color 0 0 0 0))
  )
  (wire (pts (xy 182.88 128.27) (xy 205.74 128.27))
    (stroke (width 0) (type default) (color 0 0 0 0))
  )
  (wire (pts (xy 198.247 204.089) (xy 198.247 206.756))
    (stroke (width 0) (type default) (color 0 0 0 0))
  )
  (wire (pts (xy 229.997 71.12) (xy 267.97 71.12))
    (stroke (width 0) (type default) (color 0 0 0 0))
  )
  (wire (pts (xy 219.71 140.97) (xy 205.74 140.97))
    (stroke (width 0) (type default) (color 0 0 0 0))
  )
  (wire (pts (xy 240.411 183.896) (xy 259.715 183.896))
    (stroke (width 0) (type default) (color 0 0 0 0))
  )
  (wire (pts (xy 203.581 183.896) (xy 203.581 181.356))
    (stroke (width 0) (type default) (color 0 0 0 0))
  )
  (wire (pts (xy 240.411 161.036) (xy 249.301 161.036))
    (stroke (width 0) (type default) (color 0 0 0 0))
  )
  (wire (pts (xy 172.72 128.27) (xy 182.88 128.27))
    (stroke (width 0) (type default) (color 0 0 0 0))
  )
  (wire (pts (xy 60.96 142.24) (xy 43.18 142.24))
    (stroke (width 0) (type default) (color 0 0 0 0))
  )
  (wire (pts (xy 240.411 188.976) (xy 241.681 188.976))
    (stroke (width 0) (type default) (color 0 0 0 0))
  )
  (wire (pts (xy 271.78 181.356) (xy 271.78 190.246))
    (stroke (width 0) (type default) (color 0 0 0 0))
  )
  (wire (pts (xy 201.041 176.276) (xy 209.931 176.276))
    (stroke (width 0) (type default) (color 0 0 0 0))
  )
  (wire (pts (xy 259.715 183.896) (xy 260.858 183.896))
    (stroke (width 0) (type default) (color 0 0 0 0))
  )
  (wire (pts (xy 191.516 194.056) (xy 198.247 194.056))
    (stroke (width 0) (type default) (color 0 0 0 0))
  )
  (wire (pts (xy 248.92 128.27) (xy 259.715 128.27))
    (stroke (width 0) (type default) (color 0 0 0 0))
  )
  (wire (pts (xy 162.941 183.896) (xy 162.941 195.961))
    (stroke (width 0) (type default) (color 0 0 0 0))
  )
  (wire (pts (xy 198.247 194.056) (xy 198.247 199.009))
    (stroke (width 0) (type default) (color 0 0 0 0))
  )
  (wire (pts (xy 259.715 183.896) (xy 259.715 192.786))
    (stroke (width 0) (type default) (color 0 0 0 0))
  )
  (wire (pts (xy 83.82 149.86) (xy 101.6 149.86))
    (stroke (width 0) (type default) (color 0 0 0 0))
  )
  (wire (pts (xy 157.861 186.436) (xy 157.861 195.961))
    (stroke (width 0) (type default) (color 0 0 0 0))
  )
  (wire (pts (xy 224.79 140.97) (xy 238.76 140.97))
    (stroke (width 0) (type default) (color 0 0 0 0))
  )
  (wire (pts (xy 178.816 168.656) (xy 180.594 168.656))
    (stroke (width 0) (type default) (color 0 0 0 0))
  )
  (wire (pts (xy 229.997 73.66) (xy 276.225 73.66))
    (stroke (width 0) (type default) (color 0 0 0 0))
  )
  (wire (pts (xy 224.79 135.509) (xy 224.79 140.97))
    (stroke (width 0) (type default) (color 0 0 0 0))
  )
  (wire (pts (xy 259.715 128.27) (xy 259.715 132.715))
    (stroke (width 0) (type default) (color 0 0 0 0))
  )
  (wire (pts (xy 251.46 64.008) (xy 251.46 66.04))
    (stroke (width 0) (type default) (color 0 0 0 0))
  )
  (wire (pts (xy 182.88 130.175) (xy 182.88 128.27))
    (stroke (width 0) (type default) (color 0 0 0 0))
  )
  (wire (pts (xy 83.82 160.02) (xy 88.9 160.02))
    (stroke (width 0) (type default) (color 0 0 0 0))
  )
  (wire (pts (xy 191.516 196.596) (xy 202.692 196.596))
    (stroke (width 0) (type default) (color 0 0 0 0))
  )
  (wire (pts (xy 238.76 140.97) (xy 240.411 140.97))
    (stroke (width 0) (type default) (color 0 0 0 0))
  )
  (wire (pts (xy 276.225 73.66) (xy 278.003 73.66))
    (stroke (width 0) (type default) (color 0 0 0 0))
  )
  (wire (pts (xy 60.96 160.02) (xy 55.88 160.02))
    (stroke (width 0) (type default) (color 0 0 0 0))
  )
  (wire (pts (xy 168.656 194.056) (xy 178.816 194.056))
    (stroke (width 0) (type default) (color 0 0 0 0))
  )
  (wire (pts (xy 251.46 66.04) (xy 278.003 66.04))
    (stroke (width 0) (type default) (color 0 0 0 0))
  )
  (wire (pts (xy 83.82 132.08) (xy 88.9 132.08))
    (stroke (width 0) (type default) (color 0 0 0 0))
  )
  (wire (pts (xy 203.581 181.356) (xy 209.931 181.356))
    (stroke (width 0) (type default) (color 0 0 0 0))
  )
  (wire (pts (xy 276.86 172.593) (xy 276.86 173.736))
    (stroke (width 0) (type default) (color 0 0 0 0))
  )
  (wire (pts (xy 249.301 168.656) (xy 240.411 168.656))
    (stroke (width 0) (type default) (color 0 0 0 0))
  )
  (wire (pts (xy 281.94 149.987) (xy 281.94 151.257))
    (stroke (width 0) (type default) (color 0 0 0 0))
  )
  (wire (pts (xy 249.555 186.436) (xy 247.65 186.436))
    (stroke (width 0) (type default) (color 0 0 0 0))
  )
  (wire (pts (xy 271.78 181.356) (xy 272.796 181.356))
    (stroke (width 0) (type default) (color 0 0 0 0))
  )
  (wire (pts (xy 180.594 167.894) (xy 180.594 168.656))
    (stroke (width 0) (type default) (color 0 0 0 0))
  )
  (wire (pts (xy 219.71 128.27) (xy 224.79 128.27))
    (stroke (width 0) (type default) (color 0 0 0 0))
  )
  (wire (pts (xy 88.9 133.35) (xy 88.9 132.08))
    (stroke (width 0) (type default) (color 0 0 0 0))
  )
  (wire (pts (xy 203.581 186.436) (xy 203.581 188.976))
    (stroke (width 0) (type default) (color 0 0 0 0))
  )
  (wire (pts (xy 224.79 130.429) (xy 224.79 128.27))
    (stroke (width 0) (type default) (color 0 0 0 0))
  )
  (wire (pts (xy 245.491 140.97) (xy 248.92 140.97))
    (stroke (width 0) (type default) (color 0 0 0 0))
  )
  (wire (pts (xy 247.65 186.436) (xy 247.65 192.659))
    (stroke (width 0) (type default) (color 0 0 0 0))
  )
  (wire (pts (xy 251.46 55.245) (xy 259.715 55.245))
    (stroke (width 0) (type default) (color 0 0 0 0))
  )
  (wire (pts (xy 307.34 128.27) (xy 307.34 135.89))
    (stroke (width 0) (type default) (color 0 0 0 0))
  )
  (wire (pts (xy 205.74 140.97) (xy 205.74 144.78))
    (stroke (width 0) (type default) (color 0 0 0 0))
  )
  (wire (pts (xy 240.411 163.576) (xy 249.301 163.576))
    (stroke (width 0) (type default) (color 0 0 0 0))
  )
  (wire (pts (xy 224.79 142.24) (xy 224.79 140.97))
    (stroke (width 0) (type default) (color 0 0 0 0))
  )
  (wire (pts (xy 55.88 160.02) (xy 55.88 163.83))
    (stroke (width 0) (type default) (color 0 0 0 0))
  )
  (wire (pts (xy 276.86 149.987) (xy 281.94 149.987))
    (stroke (width 0) (type default) (color 0 0 0 0))
  )
  (wire (pts (xy 157.861 186.436) (xy 203.581 186.436))
    (stroke (width 0) (type default) (color 0 0 0 0))
  )
  (wire (pts (xy 241.681 195.326) (xy 241.681 197.866))
    (stroke (width 0) (type default) (color 0 0 0 0))
  )
  (wire (pts (xy 60.96 132.08) (xy 55.88 132.08))
    (stroke (width 0) (type default) (color 0 0 0 0))
  )
  (wire (pts (xy 281.94 176.276) (xy 288.544 176.276))
    (stroke (width 0) (type default) (color 0 0 0 0))
  )
  (wire (pts (xy 267.97 55.245) (xy 267.97 58.928))
    (stroke (width 0) (type default) (color 0 0 0 0))
  )
  (wire (pts (xy 267.97 64.008) (xy 267.97 71.12))
    (stroke (width 0) (type default) (color 0 0 0 0))
  )
  (wire (pts (xy 178.816 196.596) (xy 186.436 196.596))
    (stroke (width 0) (type default) (color 0 0 0 0))
  )

  (text "USB-C PD controller " (at 13.97 19.05 0)
    (effects (font (size 2.9972 2.9972) (thickness 0.5994) bold) (justify left bottom))
  )

  (label "DISCH" (at 200.406 166.116 0)
    (effects (font (size 1.27 1.27)) (justify left bottom))
  )
  (label "AB_SIDE" (at 249.301 168.656 180)
    (effects (font (size 1.27 1.27)) (justify right bottom))
  )
  (label "PD_CC2" (at 101.6 149.86 180)
    (effects (font (size 1.27 1.27)) (justify right bottom))
  )
  (label "PD_VBUS" (at 101.6 152.4 180)
    (effects (font (size 1.27 1.27)) (justify right bottom))
  )
  (label "ATTACH" (at 234.95 73.66 0)
    (effects (font (size 1.27 1.27)) (justify left bottom))
  )
  (label "PD_VBUS" (at 241.3 181.356 0)
    (effects (font (size 1.27 1.27)) (justify left bottom))
  )
  (label "STUSB4500_PWR_OK2" (at 262.255 173.736 180)
    (effects (font (size 1.27 1.27)) (justify right bottom))
  )
  (label "ALERT" (at 234.95 66.04 0)
    (effects (font (size 1.27 1.27)) (justify left bottom))
  )
  (label "VS_DISCH" (at 200.406 161.036 0)
    (effects (font (size 1.27 1.27)) (justify left bottom))
  )
  (label "PD_CC1" (at 142.621 183.896 0)
    (effects (font (size 1.27 1.27)) (justify left bottom))
  )
  (label "GPIO" (at 234.95 71.12 0)
    (effects (font (size 1.27 1.27)) (justify left bottom))
  )
  (label "VREG_2V7" (at 168.656 194.056 0)
    (effects (font (size 1.27 1.27)) (justify left bottom))
  )
  (label "PD_VBUS" (at 172.72 128.27 0)
    (effects (font (size 1.27 1.27)) (justify left bottom))
  )
  (label "EN_SINK" (at 224.79 157.48 90)
    (effects (font (size 1.27 1.27)) (justify left bottom))
  )
  (label "PD_CC2" (at 142.621 186.436 0)
    (effects (font (size 1.27 1.27)) (justify left bottom))
  )
  (label "PD_VBUS" (at 101.6 139.7 180)
    (effects (font (size 1.27 1.27)) (justify right bottom))
  )
  (label "PD_CC1" (at 43.18 142.24 0)
    (effects (font (size 1.27 1.27)) (justify left bottom))
  )
  (label "ALERT" (at 249.301 161.036 180)
    (effects (font (size 1.27 1.27)) (justify right bottom))
  )
  (label "VREG_1V2" (at 241.3 183.896 0)
    (effects (font (size 1.27 1.27)) (justify left bottom))
  )
  (label "VREG_2V7" (at 241.3 186.436 0)
    (effects (font (size 1.27 1.27)) (justify left bottom))
  )
  (label "STUSB4500_PWR_OK3" (at 262.255 176.276 180)
    (effects (font (size 1.27 1.27)) (justify right bottom))
  )
  (label "VS_DISCH" (at 219.71 157.48 90)
    (effects (font (size 1.27 1.27)) (justify left bottom))
  )
  (label "AB_SIDE" (at 234.95 68.58 0)
    (effects (font (size 1.27 1.27)) (justify left bottom))
  )
  (label "PD_VBUS" (at 43.18 152.4 0)
    (effects (font (size 1.27 1.27)) (justify left bottom))
  )
  (label "PD_VBUS" (at 43.18 139.7 0)
    (effects (font (size 1.27 1.27)) (justify left bottom))
  )
  (label "DISCH" (at 259.715 149.86 90)
    (effects (font (size 1.27 1.27)) (justify left bottom))
  )
  (label "EN_SINK" (at 200.406 163.576 0)
    (effects (font (size 1.27 1.27)) (justify left bottom))
  )
  (label "GPIO" (at 249.301 166.116 180)
    (effects (font (size 1.27 1.27)) (justify right bottom))
  )
  (label "ATTACH" (at 249.301 163.576 180)
    (effects (font (size 1.27 1.27)) (justify right bottom))
  )

  (global_label "USB_PD_DISABLE" (shape input) (at 173.736 168.656 180) (fields_autoplaced)
    (effects (font (size 1.27 1.27)) (justify right))
    (property "Intersheet References" "${INTERSHEET_REFS}" (id 0) (at 1.651 4.826 0)
      (effects (font (size 1.27 1.27)) hide)
    )
  )
  (global_label "5V_SYS" (shape input) (at 275.59 149.987 180) (fields_autoplaced)
    (effects (font (size 1.27 1.27)) (justify right))
    (property "Intersheet References" "${INTERSHEET_REFS}" (id 0) (at 4.445 0.127 0)
      (effects (font (size 1.27 1.27)) hide)
    )
  )
  (global_label "STUSB4500_AB_SIDE" (shape output) (at 217.17 68.58 180) (fields_autoplaced)
    (effects (font (size 1.27 1.27)) (justify right))
    (property "Intersheet References" "${INTERSHEET_REFS}" (id 0) (at 0 0 0)
      (effects (font (size 1.27 1.27)) hide)
    )
  )
  (global_label "STUSB4500_ALERT" (shape output) (at 217.17 66.04 180) (fields_autoplaced)
    (effects (font (size 1.27 1.27)) (justify right))
    (property "Intersheet References" "${INTERSHEET_REFS}" (id 0) (at 0 0 0)
      (effects (font (size 1.27 1.27)) hide)
    )
  )
  (global_label "STUSB4500_GPIO" (shape output) (at 217.17 71.12 180) (fields_autoplaced)
    (effects (font (size 1.27 1.27)) (justify right))
    (property "Intersheet References" "${INTERSHEET_REFS}" (id 0) (at 0 0 0)
      (effects (font (size 1.27 1.27)) hide)
    )
  )
  (global_label "PD_VDD" (shape output) (at 309.245 128.27 0) (fields_autoplaced)
    (effects (font (size 1.27 1.27)) (justify left))
    (property "Intersheet References" "${INTERSHEET_REFS}" (id 0) (at 0 0 0)
      (effects (font (size 1.27 1.27)) hide)
    )
  )
  (global_label "I2C10_SDA" (shape bidirectional) (at 201.041 176.276 180) (fields_autoplaced)
    (effects (font (size 1.27 1.27)) (justify right))
    (property "Intersheet References" "${INTERSHEET_REFS}" (id 0) (at 1.651 4.826 0)
      (effects (font (size 1.27 1.27)) hide)
    )
  )
  (global_label "VREG_S4A_1V8" (shape input) (at 247.65 55.245 180) (fields_autoplaced)
    (effects (font (size 1.27 1.27)) (justify right))
    (property "Intersheet References" "${INTERSHEET_REFS}" (id 0) (at 0 0 0)
      (effects (font (size 1.27 1.27)) hide)
    )
  )
  (global_label "STUSB4500_ATTACH" (shape output) (at 217.17 73.66 180) (fields_autoplaced)
    (effects (font (size 1.27 1.27)) (justify right))
    (property "Intersheet References" "${INTERSHEET_REFS}" (id 0) (at 0 0 0)
      (effects (font (size 1.27 1.27)) hide)
    )
  )
  (global_label "I2C10_SCL" (shape output) (at 201.041 173.736 180) (fields_autoplaced)
    (effects (font (size 1.27 1.27)) (justify right))
    (property "Intersheet References" "${INTERSHEET_REFS}" (id 0) (at 1.651 4.826 0)
      (effects (font (size 1.27 1.27)) hide)
    )
  )

  (symbol (lib_id "sa800u-baseboard-hw:C_1u_0402") (at 259.715 192.786 270) (unit 1)
    (in_bom yes) (on_board yes) (fields_autoplaced)
    (property "Reference" "C156" (id 0) (at 262.89 194.0623 90)
      (effects (font (size 1.524 1.524)) (justify left))
    )
    (property "Value" "C_1u_0402" (id 1) (at 255.905 192.786 0)
      (effects (font (size 1.524 1.524)) hide)
    )
    (property "Footprint" "sa800u-baseboard-hw-footprints:C_0402_1005Metric" (id 2) (at 264.795 197.866 0)
      (effects (font (size 1.524 1.524)) (justify left) hide)
    )
    (property "Datasheet" " " (id 3) (at 259.715 192.786 0)
      (effects (font (size 1.27 1.27)) hide)
    )
    (property "Manufacturer" "TDK" (id 4) (at 269.875 197.866 0)
      (effects (font (size 1.524 1.524)) (justify left) hide)
    )
    (property "MPN" "C1005X6S1A105K050BC" (id 5) (at 267.335 197.866 0)
      (effects (font (size 1.524 1.524)) (justify left) hide)
    )
    (property "Val" "1u" (id 6) (at 262.89 197.2372 90)
      (effects (font (size 1.27 1.27)) (justify left))
    )
    (property "License" "Apache-2.0" (id 7) (at 236.855 213.106 0)
      (effects (font (size 1.27 1.27) (thickness 0.15)) (justify left bottom) hide)
    )
    (property "Author" "Antmicro" (id 8) (at 234.315 213.106 0)
      (effects (font (size 1.27 1.27) (thickness 0.15)) (justify left bottom) hide)
    )
    (property "Voltage" "" (id 9) (at 231.775 213.106 0)
      (effects (font (size 1.27 1.27)) (justify left bottom) hide)
    )
    (property "Dielectric" "" (id 10) (at 229.235 213.106 0)
      (effects (font (size 1.27 1.27)) (justify left bottom) hide)
    )
    (pin "1")
    (pin "2")
  )

  (symbol (lib_id "sa800u-baseboard-hw:C_1u_0402") (at 247.65 192.659 270) (unit 1)
    (in_bom yes) (on_board yes) (fields_autoplaced)
    (property "Reference" "C154" (id 0) (at 250.19 193.9353 90)
      (effects (font (size 1.524 1.524)) (justify left))
    )
    (property "Value" "C_1u_0402" (id 1) (at 243.84 192.659 0)
      (effects (font (size 1.524 1.524)) hide)
    )
    (property "Footprint" "sa800u-baseboard-hw-footprints:C_0402_1005Metric" (id 2) (at 252.73 197.739 0)
      (effects (font (size 1.524 1.524)) (justify left) hide)
    )
    (property "Datasheet" " " (id 3) (at 247.65 192.659 0)
      (effects (font (size 1.27 1.27)) hide)
    )
    (property "Manufacturer" "TDK" (id 4) (at 257.81 197.739 0)
      (effects (font (size 1.524 1.524)) (justify left) hide)
    )
    (property "MPN" "C1005X6S1A105K050BC" (id 5) (at 255.27 197.739 0)
      (effects (font (size 1.524 1.524)) (justify left) hide)
    )
    (property "Val" "1u" (id 6) (at 250.19 197.1102 90)
      (effects (font (size 1.27 1.27)) (justify left))
    )
    (property "License" "Apache-2.0" (id 7) (at 224.79 212.979 0)
      (effects (font (size 1.27 1.27) (thickness 0.15)) (justify left bottom) hide)
    )
    (property "Author" "Antmicro" (id 8) (at 222.25 212.979 0)
      (effects (font (size 1.27 1.27) (thickness 0.15)) (justify left bottom) hide)
    )
    (property "Voltage" "" (id 9) (at 219.71 212.979 0)
      (effects (font (size 1.27 1.27)) (justify left bottom) hide)
    )
    (property "Dielectric" "" (id 10) (at 217.17 212.979 0)
      (effects (font (size 1.27 1.27)) (justify left bottom) hide)
    )
    (pin "1")
    (pin "2")
  )

  (symbol (lib_id "sa800u-baseboard-hw:C_1u_0402") (at 271.78 190.246 270) (unit 1)
    (in_bom yes) (on_board yes) (fields_autoplaced)
    (property "Reference" "C157" (id 0) (at 274.193 191.5223 90)
      (effects (font (size 1.524 1.524)) (justify left))
    )
    (property "Value" "C_1u_0402" (id 1) (at 267.97 190.246 0)
      (effects (font (size 1.524 1.524)) hide)
    )
    (property "Footprint" "sa800u-baseboard-hw-footprints:C_0402_1005Metric" (id 2) (at 276.86 195.326 0)
      (effects (font (size 1.524 1.524)) (justify left) hide)
    )
    (property "Datasheet" " " (id 3) (at 271.78 190.246 0)
      (effects (font (size 1.27 1.27)) hide)
    )
    (property "Manufacturer" "TDK" (id 4) (at 281.94 195.326 0)
      (effects (font (size 1.524 1.524)) (justify left) hide)
    )
    (property "MPN" "C1005X6S1A105K050BC" (id 5) (at 279.4 195.326 0)
      (effects (font (size 1.524 1.524)) (justify left) hide)
    )
    (property "Val" "1u" (id 6) (at 274.193 194.6972 90)
      (effects (font (size 1.27 1.27)) (justify left))
    )
    (property "License" "Apache-2.0" (id 7) (at 248.92 210.566 0)
      (effects (font (size 1.27 1.27) (thickness 0.15)) (justify left bottom) hide)
    )
    (property "Author" "Antmicro" (id 8) (at 246.38 210.566 0)
      (effects (font (size 1.27 1.27) (thickness 0.15)) (justify left bottom) hide)
    )
    (property "Voltage" "" (id 9) (at 243.84 210.566 0)
      (effects (font (size 1.27 1.27)) (justify left bottom) hide)
    )
    (property "Dielectric" "" (id 10) (at 241.3 210.566 0)
      (effects (font (size 1.27 1.27)) (justify left bottom) hide)
    )
    (pin "1")
    (pin "2")
  )

  (symbol (lib_id "sa800u-baseboard-hw:STUSB4500_QFN") (at 209.931 163.576 0) (unit 1)
    (in_bom yes) (on_board yes) (fields_autoplaced)
    (property "Reference" "U23" (id 0) (at 225.171 203.2 0))
    (property "Value" "STUSB4500_QFN" (id 1) (at 255.651 173.736 0)
      (effects (font (size 1.27 1.27) (thickness 0.15)) (justify left bottom) hide)
    )
    (property "Footprint" "sa800u-baseboard-hw-footprints:QFN-24-1EP_4x4mm_EP2.1x2.1mm" (id 2) (at 255.651 176.276 0)
      (effects (font (size 1.27 1.27) (thickness 0.15)) (justify left bottom) hide)
    )
    (property "Datasheet" "https://www.mouser.pl/datasheet/2/389/dm00489312-1799262.pdf" (id 3) (at 255.651 178.816 0)
      (effects (font (size 1.27 1.27) (thickness 0.15)) (justify left bottom) hide)
    )
    (property "MPN" "STUSB4500QTR" (id 4) (at 225.171 205.74 0)
      (effects (font (size 1.27 1.27) (thickness 0.15)))
    )
    (property "Manufacturer" "STMicroelectronics" (id 5) (at 255.651 181.356 0)
      (effects (font (size 1.27 1.27) (thickness 0.15)) (justify left bottom) hide)
    )
    (property "Author" "Antmicro" (id 6) (at 255.651 183.896 0)
      (effects (font (size 1.27 1.27) (thickness 0.15)) (justify left bottom) hide)
    )
    (property "License" "Apache-2.0" (id 7) (at 255.651 186.436 0)
      (effects (font (size 1.27 1.27) (thickness 0.15)) (justify left bottom) hide)
    )
    (pin "1")
    (pin "10")
    (pin "11")
    (pin "12")
    (pin "13")
    (pin "14")
    (pin "15")
    (pin "16")
    (pin "17")
    (pin "18")
    (pin "19")
    (pin "2")
    (pin "20")
    (pin "21")
    (pin "22")
    (pin "23")
    (pin "24")
    (pin "25")
    (pin "3")
    (pin "4")
    (pin "5")
    (pin "6")
    (pin "7")
    (pin "8")
    (pin "9")
  )

  (symbol (lib_id "sa800u-baseboard-hw:GND") (at 55.88 163.83 0) (unit 1)
    (in_bom yes) (on_board yes) (fields_autoplaced)
    (property "Reference" "#PWR0252" (id 0) (at 55.88 170.18 0)
      (effects (font (size 1.27 1.27)) hide)
    )
    (property "Value" "GND" (id 1) (at 55.88 168.91 0))
    (property "Footprint" "" (id 2) (at 55.88 163.83 0)
      (effects (font (size 1.27 1.27)) hide)
    )
    (property "Datasheet" "" (id 3) (at 55.88 163.83 0)
      (effects (font (size 1.27 1.27)) hide)
    )
    (property "Author" "Antmicro" (id 4) (at 64.77 171.45 0)
      (effects (font (size 1.27 1.27) (thickness 0.15)) (justify left bottom) hide)
    )
    (property "License" "Apache-2.0" (id 5) (at 64.77 173.99 0)
      (effects (font (size 1.27 1.27) (thickness 0.15)) (justify left bottom) hide)
    )
    (pin "1")
  )

  (symbol (lib_id "sa800u-baseboard-hw:GND") (at 88.9 162.56 0) (unit 1)
    (in_bom yes) (on_board yes) (fields_autoplaced)
    (property "Reference" "#PWR0255" (id 0) (at 88.9 168.91 0)
      (effects (font (size 1.27 1.27)) hide)
    )
    (property "Value" "GND" (id 1) (at 88.9 167.64 0))
    (property "Footprint" "" (id 2) (at 88.9 162.56 0)
      (effects (font (size 1.27 1.27)) hide)
    )
    (property "Datasheet" "" (id 3) (at 88.9 162.56 0)
      (effects (font (size 1.27 1.27)) hide)
    )
    (property "Author" "Antmicro" (id 4) (at 97.79 170.18 0)
      (effects (font (size 1.27 1.27) (thickness 0.15)) (justify left bottom) hide)
    )
    (property "License" "Apache-2.0" (id 5) (at 97.79 172.72 0)
      (effects (font (size 1.27 1.27) (thickness 0.15)) (justify left bottom) hide)
    )
    (pin "1")
  )

  (symbol (lib_id "sa800u-baseboard-hw:GND") (at 88.9 133.35 0) (unit 1)
    (in_bom yes) (on_board yes) (fields_autoplaced)
    (property "Reference" "#PWR0254" (id 0) (at 88.9 139.7 0)
      (effects (font (size 1.27 1.27)) hide)
    )
    (property "Value" "GND" (id 1) (at 88.9 138.43 0))
    (property "Footprint" "" (id 2) (at 88.9 133.35 0)
      (effects (font (size 1.27 1.27)) hide)
    )
    (property "Datasheet" "" (id 3) (at 88.9 133.35 0)
      (effects (font (size 1.27 1.27)) hide)
    )
    (property "Author" "Antmicro" (id 4) (at 97.79 140.97 0)
      (effects (font (size 1.27 1.27) (thickness 0.15)) (justify left bottom) hide)
    )
    (property "License" "Apache-2.0" (id 5) (at 97.79 143.51 0)
      (effects (font (size 1.27 1.27) (thickness 0.15)) (justify left bottom) hide)
    )
    (pin "1")
  )

  (symbol (lib_id "sa800u-baseboard-hw:GND") (at 55.88 133.35 0) (unit 1)
    (in_bom yes) (on_board yes) (fields_autoplaced)
    (property "Reference" "#PWR0251" (id 0) (at 55.88 139.7 0)
      (effects (font (size 1.27 1.27)) hide)
    )
    (property "Value" "GND" (id 1) (at 53.34 134.6199 0)
      (effects (font (size 1.27 1.27)) (justify right))
    )
    (property "Footprint" "" (id 2) (at 55.88 133.35 0)
      (effects (font (size 1.27 1.27)) hide)
    )
    (property "Datasheet" "" (id 3) (at 55.88 133.35 0)
      (effects (font (size 1.27 1.27)) hide)
    )
    (property "Author" "Antmicro" (id 4) (at 64.77 140.97 0)
      (effects (font (size 1.27 1.27) (thickness 0.15)) (justify left bottom) hide)
    )
    (property "License" "Apache-2.0" (id 5) (at 64.77 143.51 0)
      (effects (font (size 1.27 1.27) (thickness 0.15)) (justify left bottom) hide)
    )
    (pin "1")
  )

  (symbol (lib_id "sa800u-baseboard-hw:C_4u7_0603") (at 182.88 130.175 270) (unit 1)
    (in_bom yes) (on_board yes) (fields_autoplaced)
    (property "Reference" "C152" (id 0) (at 179.832 131.4513 90)
      (effects (font (size 1.524 1.524)) (justify right))
    )
    (property "Value" "C_4u7_0603" (id 1) (at 179.07 130.175 0)
      (effects (font (size 1.524 1.524)) hide)
    )
    (property "Footprint" "sa800u-baseboard-hw-footprints:C_0603_1608Metric" (id 2) (at 187.96 135.255 0)
      (effects (font (size 1.524 1.524)) (justify left) hide)
    )
    (property "Datasheet" " " (id 3) (at 182.88 130.175 0)
      (effects (font (size 1.27 1.27)) hide)
    )
    (property "Manufacturer" "TDK" (id 4) (at 193.04 135.255 0)
      (effects (font (size 1.524 1.524)) (justify left) hide)
    )
    (property "MPN" "C1608X5R1V475M080AC" (id 5) (at 190.5 135.255 0)
      (effects (font (size 1.524 1.524)) (justify left) hide)
    )
    (property "Val" "4u7" (id 6) (at 179.832 134.6262 90)
      (effects (font (size 1.27 1.27)) (justify right))
    )
    (property "License" "Apache-2.0" (id 7) (at 160.02 150.495 0)
      (effects (font (size 1.27 1.27) (thickness 0.15)) (justify left bottom) hide)
    )
    (property "Author" "Antmicro" (id 8) (at 157.48 150.495 0)
      (effects (font (size 1.27 1.27) (thickness 0.15)) (justify left bottom) hide)
    )
    (property "Voltage" "" (id 9) (at 154.94 150.495 0)
      (effects (font (size 1.27 1.27)) (justify left bottom) hide)
    )
    (property "Dielectric" "" (id 10) (at 152.4 150.495 0)
      (effects (font (size 1.27 1.27)) (justify left bottom) hide)
    )
    (pin "1")
    (pin "2")
  )

  (symbol (lib_id "sa800u-baseboard-hw:R_470R_0402") (at 219.71 130.429 270) (unit 1)
    (in_bom yes) (on_board yes) (fields_autoplaced)
    (property "Reference" "R158" (id 0) (at 217.17 131.699 90)
      (effects (font (size 1.524 1.524)) (justify right))
    )
    (property "Value" "R_470R_0402" (id 1) (at 215.9 130.429 0)
      (effects (font (size 1.524 1.524)) hide)
    )
    (property "Footprint" "sa800u-baseboard-hw-footprints:R_0402_1005Metric" (id 2) (at 224.79 135.509 0)
      (effects (font (size 1.524 1.524)) (justify left) hide)
    )
    (property "Datasheet" "https://www.bourns.com/docs/product-datasheets/cr.pdf" (id 3) (at 219.71 130.429 0)
      (effects (font (size 1.27 1.27)) hide)
    )
    (property "Manufacturer" "Bourns" (id 4) (at 229.87 135.509 0)
      (effects (font (size 1.524 1.524)) (justify left) hide)
    )
    (property "MPN" "CR0402-FX-4700GLF" (id 5) (at 227.33 135.509 0)
      (effects (font (size 1.524 1.524)) (justify left) hide)
    )
    (property "Val" "470R" (id 6) (at 217.17 134.8739 90)
      (effects (font (size 1.27 1.27)) (justify right))
    )
    (property "License" "Apache-2.0" (id 7) (at 194.31 150.749 0)
      (effects (font (size 1.27 1.27) (thickness 0.15)) (justify left bottom) hide)
    )
    (property "Author" "Antmicro" (id 8) (at 191.77 150.749 0)
      (effects (font (size 1.27 1.27) (thickness 0.15)) (justify left bottom) hide)
    )
    (property "Tolerance" "1%" (id 9) (at 209.55 150.749 0)
      (effects (font (size 1.27 1.27)) (justify left bottom) hide)
    )
    (pin "1")
    (pin "2")
  )

  (symbol (lib_id "sa800u-baseboard-hw:R_1k_0402") (at 219.71 142.24 270) (unit 1)
    (in_bom yes) (on_board yes) (fields_autoplaced)
    (property "Reference" "R159" (id 0) (at 217.17 143.51 90)
      (effects (font (size 1.524 1.524)) (justify right))
    )
    (property "Value" "R_1k_0402" (id 1) (at 215.9 142.24 0)
      (effects (font (size 1.524 1.524)) hide)
    )
    (property "Footprint" "sa800u-baseboard-hw-footprints:R_0402_1005Metric" (id 2) (at 224.79 147.32 0)
      (effects (font (size 1.524 1.524)) (justify left) hide)
    )
    (property "Datasheet" "https://www.bourns.com/docs/product-datasheets/cr.pdf" (id 3) (at 219.71 142.24 0)
      (effects (font (size 1.27 1.27)) hide)
    )
    (property "Manufacturer" "Bourns" (id 4) (at 229.87 147.32 0)
      (effects (font (size 1.524 1.524)) (justify left) hide)
    )
    (property "MPN" "CR0402-FX-1001GLF" (id 5) (at 227.33 147.32 0)
      (effects (font (size 1.524 1.524)) (justify left) hide)
    )
    (property "Val" "1k" (id 6) (at 217.17 146.6849 90)
      (effects (font (size 1.27 1.27)) (justify right))
    )
    (property "License" "Apache-2.0" (id 7) (at 194.31 162.56 0)
      (effects (font (size 1.27 1.27) (thickness 0.15)) (justify left bottom) hide)
    )
    (property "Author" "Antmicro" (id 8) (at 191.77 162.56 0)
      (effects (font (size 1.27 1.27) (thickness 0.15)) (justify left bottom) hide)
    )
    (property "Tolerance" "1%" (id 9) (at 209.55 162.56 0)
      (effects (font (size 1.27 1.27)) (justify left bottom) hide)
    )
    (pin "1")
    (pin "2")
  )

  (symbol (lib_id "sa800u-baseboard-hw:C_1u_0603") (at 205.74 144.78 270) (unit 1)
    (in_bom yes) (on_board yes) (fields_autoplaced)
    (property "Reference" "C153" (id 0) (at 203.073 146.0563 90)
      (effects (font (size 1.524 1.524)) (justify right))
    )
    (property "Value" "C_1u_0603" (id 1) (at 201.93 144.78 0)
      (effects (font (size 1.524 1.524)) hide)
    )
    (property "Footprint" "sa800u-baseboard-hw-footprints:C_0603_1608Metric" (id 2) (at 210.82 149.86 0)
      (effects (font (size 1.524 1.524)) (justify left) hide)
    )
    (property "Datasheet" " " (id 3) (at 205.74 144.78 0)
      (effects (font (size 1.27 1.27)) hide)
    )
    (property "Manufacturer" "Walsin" (id 4) (at 215.9 149.86 0)
      (effects (font (size 1.524 1.524)) (justify left) hide)
    )
    (property "MPN" "0603YD105KAT2A" (id 5) (at 213.36 149.86 0)
      (effects (font (size 1.524 1.524)) (justify left) hide)
    )
    (property "Val" "1u" (id 6) (at 203.073 149.2312 90)
      (effects (font (size 1.27 1.27)) (justify right))
    )
    (property "License" "Apache-2.0" (id 7) (at 182.88 165.1 0)
      (effects (font (size 1.27 1.27) (thickness 0.15)) (justify left bottom) hide)
    )
    (property "Author" "Antmicro" (id 8) (at 180.34 165.1 0)
      (effects (font (size 1.27 1.27) (thickness 0.15)) (justify left bottom) hide)
    )
    (property "Voltage" "" (id 9) (at 177.8 165.1 0)
      (effects (font (size 1.27 1.27)) (justify left bottom) hide)
    )
    (property "Dielectric" "" (id 10) (at 175.26 165.1 0)
      (effects (font (size 1.27 1.27)) (justify left bottom) hide)
    )
    (pin "1")
    (pin "2")
  )

  (symbol (lib_id "sa800u-baseboard-hw:GND") (at 205.74 149.86 0) (unit 1)
    (in_bom yes) (on_board yes) (fields_autoplaced)
    (property "Reference" "#PWR0262" (id 0) (at 205.74 156.21 0)
      (effects (font (size 1.27 1.27)) hide)
    )
    (property "Value" "GND" (id 1) (at 205.74 154.94 0))
    (property "Footprint" "" (id 2) (at 205.74 149.86 0)
      (effects (font (size 1.27 1.27)) hide)
    )
    (property "Datasheet" "" (id 3) (at 205.74 149.86 0)
      (effects (font (size 1.27 1.27)) hide)
    )
    (property "Author" "Antmicro" (id 4) (at 214.63 157.48 0)
      (effects (font (size 1.27 1.27) (thickness 0.15)) (justify left bottom) hide)
    )
    (property "License" "Apache-2.0" (id 5) (at 214.63 160.02 0)
      (effects (font (size 1.27 1.27) (thickness 0.15)) (justify left bottom) hide)
    )
    (pin "1")
  )

  (symbol (lib_id "sa800u-baseboard-hw:PMEG6002EJ,115") (at 205.74 129.54 270) (unit 1)
    (in_bom yes) (on_board yes) (fields_autoplaced)
    (property "Reference" "D35" (id 0) (at 203.2 132.3339 90)
      (effects (font (size 1.27 1.27)) (justify right))
    )
    (property "Value" "PMEG6002EJ,115" (id 1) (at 203.2 134.8739 90)
      (effects (font (size 1.27 1.27)) (justify right))
    )
    (property "Footprint" "sa800u-baseboard-hw-footprints:D_SOD-323F" (id 2) (at 205.74 129.54 0)
      (effects (font (size 1.27 1.27)) hide)
    )
    (property "Datasheet" "https://www.farnell.com/datasheets/1443391.pdf" (id 3) (at 205.74 129.54 0)
      (effects (font (size 1.27 1.27)) hide)
    )
    (property "MPN" "PMEG6002EJ,115" (id 4) (at 205.74 129.54 0)
      (effects (font (size 1.27 1.27)) hide)
    )
    (property "Manufacturer" "Nexperia" (id 5) (at 205.74 129.54 0)
      (effects (font (size 1.27 1.27)) hide)
    )
    (property "Author" "Antmicro" (id 6) (at 185.42 151.13 0)
      (effects (font (size 1.27 1.27) (thickness 0.15)) (justify left bottom) hide)
    )
    (property "License" "Apache-2.0" (id 7) (at 182.88 151.13 0)
      (effects (font (size 1.27 1.27) (thickness 0.15)) (justify left bottom) hide)
    )
    (pin "A")
    (pin "K")
  )

  (symbol (lib_id "sa800u-baseboard-hw:R_100k_0402") (at 224.79 130.429 270) (unit 1)
    (in_bom yes) (on_board yes) (fields_autoplaced)
    (property "Reference" "R160" (id 0) (at 227.33 131.699 90)
      (effects (font (size 1.524 1.524)) (justify left))
    )
    (property "Value" "R_100k_0402" (id 1) (at 220.98 130.429 0)
      (effects (font (size 1.524 1.524)) hide)
    )
    (property "Footprint" "sa800u-baseboard-hw-footprints:R_0402_1005Metric" (id 2) (at 229.87 135.509 0)
      (effects (font (size 1.524 1.524)) (justify left) hide)
    )
    (property "Datasheet" "https://www.bourns.com/docs/product-datasheets/cr.pdf" (id 3) (at 224.79 130.429 0)
      (effects (font (size 1.27 1.27)) hide)
    )
    (property "Manufacturer" "Bourns" (id 4) (at 234.95 135.509 0)
      (effects (font (size 1.524 1.524)) (justify left) hide)
    )
    (property "MPN" "CR0402-FX-1003GLF" (id 5) (at 232.41 135.509 0)
      (effects (font (size 1.524 1.524)) (justify left) hide)
    )
    (property "Val" "100k" (id 6) (at 227.33 134.8739 90)
      (effects (font (size 1.27 1.27)) (justify left))
    )
    (property "License" "Apache-2.0" (id 7) (at 199.39 150.749 0)
      (effects (font (size 1.27 1.27) (thickness 0.15)) (justify left bottom) hide)
    )
    (property "Author" "Antmicro" (id 8) (at 196.85 150.749 0)
      (effects (font (size 1.27 1.27) (thickness 0.15)) (justify left bottom) hide)
    )
    (property "Tolerance" "1%" (id 9) (at 214.63 150.749 0)
      (effects (font (size 1.27 1.27)) (justify left bottom) hide)
    )
    (pin "1")
    (pin "2")
  )

  (symbol (lib_id "sa800u-baseboard-hw:R_22k_0402") (at 224.79 142.24 270) (unit 1)
    (in_bom yes) (on_board yes) (fields_autoplaced)
    (property "Reference" "R161" (id 0) (at 227.33 143.51 90)
      (effects (font (size 1.524 1.524)) (justify left))
    )
    (property "Value" "R_22k_0402" (id 1) (at 220.98 142.24 0)
      (effects (font (size 1.524 1.524)) hide)
    )
    (property "Footprint" "sa800u-baseboard-hw-footprints:R_0402_1005Metric" (id 2) (at 229.87 147.32 0)
      (effects (font (size 1.524 1.524)) (justify left) hide)
    )
    (property "Datasheet" "https://www.bourns.com/docs/product-datasheets/cr.pdf" (id 3) (at 224.79 142.24 0)
      (effects (font (size 1.27 1.27)) hide)
    )
    (property "Manufacturer" "Bourns" (id 4) (at 234.95 147.32 0)
      (effects (font (size 1.524 1.524)) (justify left) hide)
    )
    (property "MPN" "CR0402-FX-2202GLF" (id 5) (at 232.41 147.32 0)
      (effects (font (size 1.524 1.524)) (justify left) hide)
    )
    (property "Val" "22k" (id 6) (at 227.33 146.6849 90)
      (effects (font (size 1.27 1.27)) (justify left))
    )
    (property "License" "Apache-2.0" (id 7) (at 199.39 162.56 0)
      (effects (font (size 1.27 1.27) (thickness 0.15)) (justify left bottom) hide)
    )
    (property "Author" "Antmicro" (id 8) (at 196.85 162.56 0)
      (effects (font (size 1.27 1.27) (thickness 0.15)) (justify left bottom) hide)
    )
    (property "Tolerance" "1%" (id 9) (at 214.63 162.56 0)
      (effects (font (size 1.27 1.27)) (justify left bottom) hide)
    )
    (pin "1")
    (pin "2")
  )

  (symbol (lib_id "sa800u-baseboard-hw:C_100n_0402") (at 248.92 132.08 270) (unit 1)
    (in_bom yes) (on_board yes) (fields_autoplaced)
    (property "Reference" "C155" (id 0) (at 251.46 133.3563 90)
      (effects (font (size 1.524 1.524)) (justify left))
    )
    (property "Value" "C_100n_0402" (id 1) (at 245.11 132.08 0)
      (effects (font (size 1.524 1.524)) hide)
    )
    (property "Footprint" "sa800u-baseboard-hw-footprints:C_0402_1005Metric" (id 2) (at 254 137.16 0)
      (effects (font (size 1.524 1.524)) (justify left) hide)
    )
    (property "Datasheet" "https://search.murata.co.jp/Ceramy/image/img/A01X/G101/ENG/GRM155R61H104KE14-01.pdf" (id 3) (at 248.92 132.08 0)
      (effects (font (size 1.27 1.27)) hide)
    )
    (property "Manufacturer" "Murata" (id 4) (at 259.08 137.16 0)
      (effects (font (size 1.524 1.524)) (justify left) hide)
    )
    (property "MPN" "GRM155R61H104KE14D" (id 5) (at 256.54 137.16 0)
      (effects (font (size 1.524 1.524)) (justify left) hide)
    )
    (property "Val" "100n" (id 6) (at 251.46 136.5312 90)
      (effects (font (size 1.27 1.27)) (justify left))
    )
    (property "License" "Apache-2.0" (id 7) (at 226.06 152.4 0)
      (effects (font (size 1.27 1.27) (thickness 0.15)) (justify left bottom) hide)
    )
    (property "Author" "Antmicro" (id 8) (at 223.52 152.4 0)
      (effects (font (size 1.27 1.27) (thickness 0.15)) (justify left bottom) hide)
    )
    (property "Voltage" "50V" (id 9) (at 220.98 152.4 0)
      (effects (font (size 1.27 1.27)) (justify left bottom) hide)
    )
    (property "Dielectric" "X5R" (id 10) (at 218.44 152.4 0)
      (effects (font (size 1.27 1.27)) (justify left bottom) hide)
    )
    (pin "1")
    (pin "2")
  )

  (symbol (lib_id "sa800u-baseboard-hw:R_100R_0402") (at 240.411 140.97 0) (unit 1)
    (in_bom yes) (on_board yes) (fields_autoplaced)
    (property "Reference" "R166" (id 0) (at 242.951 144.78 0)
      (effects (font (size 1.524 1.524)))
    )
    (property "Value" "R_100R_0402" (id 1) (at 240.411 144.78 0)
      (effects (font (size 1.524 1.524)) hide)
    )
    (property "Footprint" "sa800u-baseboard-hw-footprints:R_0402_1005Metric" (id 2) (at 245.491 135.89 0)
      (effects (font (size 1.524 1.524)) (justify left) hide)
    )
    (property "Datasheet" "https://www.bourns.com/docs/product-datasheets/cr.pdf" (id 3) (at 240.411 140.97 0)
      (effects (font (size 1.27 1.27)) hide)
    )
    (property "Manufacturer" "Bourns" (id 4) (at 245.491 130.81 0)
      (effects (font (size 1.524 1.524)) (justify left) hide)
    )
    (property "MPN" "CR0402-FX-1000GLF" (id 5) (at 245.491 133.35 0)
      (effects (font (size 1.524 1.524)) (justify left) hide)
    )
    (property "Val" "100R" (id 6) (at 242.951 148.59 0))
    (property "License" "Apache-2.0" (id 7) (at 260.731 166.37 0)
      (effects (font (size 1.27 1.27) (thickness 0.15)) (justify left bottom) hide)
    )
    (property "Author" "Antmicro" (id 8) (at 260.731 168.91 0)
      (effects (font (size 1.27 1.27) (thickness 0.15)) (justify left bottom) hide)
    )
    (property "Tolerance" "1%" (id 9) (at 260.731 151.13 0)
      (effects (font (size 1.27 1.27)) (justify left bottom) hide)
    )
    (pin "1")
    (pin "2")
  )

  (symbol (lib_id "sa800u-baseboard-hw:R_1k1_0402") (at 259.715 132.715 270) (unit 1)
    (in_bom yes) (on_board yes) (fields_autoplaced)
    (property "Reference" "R169" (id 0) (at 261.62 133.985 90)
      (effects (font (size 1.524 1.524)) (justify left))
    )
    (property "Value" "R_1k1_0402" (id 1) (at 255.905 132.715 0)
      (effects (font (size 1.524 1.524)) hide)
    )
    (property "Footprint" "sa800u-baseboard-hw-footprints:R_0402_1005Metric" (id 2) (at 264.795 137.795 0)
      (effects (font (size 1.524 1.524)) (justify left) hide)
    )
    (property "Datasheet" "https://www.bourns.com/docs/product-datasheets/cr.pdf" (id 3) (at 259.715 132.715 0)
      (effects (font (size 1.27 1.27)) hide)
    )
    (property "Manufacturer" "Bourns" (id 4) (at 269.875 137.795 0)
      (effects (font (size 1.524 1.524)) (justify left) hide)
    )
    (property "MPN" "CR0402-FX-1101GLF" (id 5) (at 267.335 137.795 0)
      (effects (font (size 1.524 1.524)) (justify left) hide)
    )
    (property "Val" "1k1" (id 6) (at 261.62 137.1599 90)
      (effects (font (size 1.27 1.27)) (justify left))
    )
    (property "License" "Apache-2.0" (id 7) (at 234.315 153.035 0)
      (effects (font (size 1.27 1.27) (thickness 0.15)) (justify left bottom) hide)
    )
    (property "Author" "Antmicro" (id 8) (at 231.775 153.035 0)
      (effects (font (size 1.27 1.27) (thickness 0.15)) (justify left bottom) hide)
    )
    (property "Tolerance" "1%" (id 9) (at 249.555 153.035 0)
      (effects (font (size 1.27 1.27)) (justify left bottom) hide)
    )
    (pin "1")
    (pin "2")
  )

  (symbol (lib_id "sa800u-baseboard-hw:GND") (at 307.34 147.32 0) (unit 1)
    (in_bom yes) (on_board yes) (fields_autoplaced)
    (property "Reference" "#PWR0269" (id 0) (at 307.34 153.67 0)
      (effects (font (size 1.27 1.27)) hide)
    )
    (property "Value" "GND" (id 1) (at 307.34 152.4 0))
    (property "Footprint" "" (id 2) (at 307.34 147.32 0)
      (effects (font (size 1.27 1.27)) hide)
    )
    (property "Datasheet" "" (id 3) (at 307.34 147.32 0)
      (effects (font (size 1.27 1.27)) hide)
    )
    (property "Author" "Antmicro" (id 4) (at 316.23 154.94 0)
      (effects (font (size 1.27 1.27) (thickness 0.15)) (justify left bottom) hide)
    )
    (property "License" "Apache-2.0" (id 5) (at 316.23 157.48 0)
      (effects (font (size 1.27 1.27) (thickness 0.15)) (justify left bottom) hide)
    )
    (pin "1")
  )

  (symbol (lib_id "sa800u-baseboard-hw:R_100k_0402") (at 186.436 194.056 0) (unit 1)
    (in_bom yes) (on_board yes)
    (property "Reference" "R154" (id 0) (at 183.896 192.913 0)
      (effects (font (size 1.524 1.524)))
    )
    (property "Value" "R_100k_0402" (id 1) (at 186.436 197.866 0)
      (effects (font (size 1.524 1.524)) hide)
    )
    (property "Footprint" "sa800u-baseboard-hw-footprints:R_0402_1005Metric" (id 2) (at 191.516 188.976 0)
      (effects (font (size 1.524 1.524)) (justify left) hide)
    )
    (property "Datasheet" "https://www.bourns.com/docs/product-datasheets/cr.pdf" (id 3) (at 186.436 194.056 0)
      (effects (font (size 1.27 1.27)) hide)
    )
    (property "Manufacturer" "Bourns" (id 4) (at 191.516 183.896 0)
      (effects (font (size 1.524 1.524)) (justify left) hide)
    )
    (property "MPN" "CR0402-FX-1003GLF" (id 5) (at 191.516 186.436 0)
      (effects (font (size 1.524 1.524)) (justify left) hide)
    )
    (property "Val" "100k" (id 6) (at 193.421 193.04 0))
    (property "DNP" "DNP" (id 7) (at 188.976 194.056 0))
    (property "License" "Apache-2.0" (id 8) (at 206.756 219.456 0)
      (effects (font (size 1.27 1.27) (thickness 0.15)) (justify left bottom) hide)
    )
    (property "Author" "Antmicro" (id 9) (at 206.756 221.996 0)
      (effects (font (size 1.27 1.27) (thickness 0.15)) (justify left bottom) hide)
    )
    (property "Tolerance" "1%" (id 10) (at 206.756 204.216 0)
      (effects (font (size 1.27 1.27)) (justify left bottom) hide)
    )
    (pin "1")
    (pin "2")
  )

  (symbol (lib_id "sa800u-baseboard-hw:R_100k_0402") (at 186.436 196.596 0) (unit 1)
    (in_bom yes) (on_board yes)
    (property "Reference" "R155" (id 0) (at 184.023 195.58 0)
      (effects (font (size 1.524 1.524)))
    )
    (property "Value" "R_100k_0402" (id 1) (at 186.436 200.406 0)
      (effects (font (size 1.524 1.524)) hide)
    )
    (property "Footprint" "sa800u-baseboard-hw-footprints:R_0402_1005Metric" (id 2) (at 191.516 191.516 0)
      (effects (font (size 1.524 1.524)) (justify left) hide)
    )
    (property "Datasheet" "https://www.bourns.com/docs/product-datasheets/cr.pdf" (id 3) (at 186.436 196.596 0)
      (effects (font (size 1.27 1.27)) hide)
    )
    (property "Manufacturer" "Bourns" (id 4) (at 191.516 186.436 0)
      (effects (font (size 1.524 1.524)) (justify left) hide)
    )
    (property "MPN" "CR0402-FX-1003GLF" (id 5) (at 191.516 188.976 0)
      (effects (font (size 1.524 1.524)) (justify left) hide)
    )
    (property "Val" "100k" (id 6) (at 193.548 195.58 0))
    (property "DNP" "DNP" (id 7) (at 188.976 196.596 0))
    (property "License" "Apache-2.0" (id 8) (at 206.756 221.996 0)
      (effects (font (size 1.27 1.27) (thickness 0.15)) (justify left bottom) hide)
    )
    (property "Author" "Antmicro" (id 9) (at 206.756 224.536 0)
      (effects (font (size 1.27 1.27) (thickness 0.15)) (justify left bottom) hide)
    )
    (property "Tolerance" "1%" (id 10) (at 206.756 206.756 0)
      (effects (font (size 1.27 1.27)) (justify left bottom) hide)
    )
    (pin "1")
    (pin "2")
  )

  (symbol (lib_id "sa800u-baseboard-hw:GND") (at 198.247 206.756 0) (unit 1)
    (in_bom yes) (on_board yes) (fields_autoplaced)
    (property "Reference" "#PWR0260" (id 0) (at 198.247 213.106 0)
      (effects (font (size 1.27 1.27)) hide)
    )
    (property "Value" "GND" (id 1) (at 198.247 211.836 0))
    (property "Footprint" "" (id 2) (at 198.247 206.756 0)
      (effects (font (size 1.27 1.27)) hide)
    )
    (property "Datasheet" "" (id 3) (at 198.247 206.756 0)
      (effects (font (size 1.27 1.27)) hide)
    )
    (property "Author" "Antmicro" (id 4) (at 207.137 214.376 0)
      (effects (font (size 1.27 1.27) (thickness 0.15)) (justify left bottom) hide)
    )
    (property "License" "Apache-2.0" (id 5) (at 207.137 216.916 0)
      (effects (font (size 1.27 1.27) (thickness 0.15)) (justify left bottom) hide)
    )
    (pin "1")
  )

  (symbol (lib_id "sa800u-baseboard-hw:GND") (at 202.692 206.756 0) (unit 1)
    (in_bom yes) (on_board yes) (fields_autoplaced)
    (property "Reference" "#PWR0261" (id 0) (at 202.692 213.106 0)
      (effects (font (size 1.27 1.27)) hide)
    )
    (property "Value" "GND" (id 1) (at 202.692 211.836 0))
    (property "Footprint" "" (id 2) (at 202.692 206.756 0)
      (effects (font (size 1.27 1.27)) hide)
    )
    (property "Datasheet" "" (id 3) (at 202.692 206.756 0)
      (effects (font (size 1.27 1.27)) hide)
    )
    (property "Author" "Antmicro" (id 4) (at 211.582 214.376 0)
      (effects (font (size 1.27 1.27) (thickness 0.15)) (justify left bottom) hide)
    )
    (property "License" "Apache-2.0" (id 5) (at 211.582 216.916 0)
      (effects (font (size 1.27 1.27) (thickness 0.15)) (justify left bottom) hide)
    )
    (pin "1")
  )

  (symbol (lib_id "sa800u-baseboard-hw:R_100k_0402") (at 198.247 199.009 270) (unit 1)
    (in_bom yes) (on_board yes) (fields_autoplaced)
    (property "Reference" "R156" (id 0) (at 196.342 200.279 90)
      (effects (font (size 1.524 1.524)) (justify right))
    )
    (property "Value" "R_100k_0402" (id 1) (at 194.437 199.009 0)
      (effects (font (size 1.524 1.524)) hide)
    )
    (property "Footprint" "sa800u-baseboard-hw-footprints:R_0402_1005Metric" (id 2) (at 203.327 204.089 0)
      (effects (font (size 1.524 1.524)) (justify left) hide)
    )
    (property "Datasheet" "https://www.bourns.com/docs/product-datasheets/cr.pdf" (id 3) (at 198.247 199.009 0)
      (effects (font (size 1.27 1.27)) hide)
    )
    (property "Manufacturer" "Bourns" (id 4) (at 208.407 204.089 0)
      (effects (font (size 1.524 1.524)) (justify left) hide)
    )
    (property "MPN" "CR0402-FX-1003GLF" (id 5) (at 205.867 204.089 0)
      (effects (font (size 1.524 1.524)) (justify left) hide)
    )
    (property "Val" "100k" (id 6) (at 196.342 203.4539 90)
      (effects (font (size 1.27 1.27)) (justify right))
    )
    (property "License" "Apache-2.0" (id 7) (at 172.847 219.329 0)
      (effects (font (size 1.27 1.27) (thickness 0.15)) (justify left bottom) hide)
    )
    (property "Author" "Antmicro" (id 8) (at 170.307 219.329 0)
      (effects (font (size 1.27 1.27) (thickness 0.15)) (justify left bottom) hide)
    )
    (property "Tolerance" "1%" (id 9) (at 188.087 219.329 0)
      (effects (font (size 1.27 1.27)) (justify left bottom) hide)
    )
    (pin "1")
    (pin "2")
  )

  (symbol (lib_id "sa800u-baseboard-hw:R_100k_0402") (at 202.692 199.009 270) (unit 1)
    (in_bom yes) (on_board yes) (fields_autoplaced)
    (property "Reference" "R157" (id 0) (at 205.232 200.279 90)
      (effects (font (size 1.524 1.524)) (justify left))
    )
    (property "Value" "R_100k_0402" (id 1) (at 198.882 199.009 0)
      (effects (font (size 1.524 1.524)) hide)
    )
    (property "Footprint" "sa800u-baseboard-hw-footprints:R_0402_1005Metric" (id 2) (at 207.772 204.089 0)
      (effects (font (size 1.524 1.524)) (justify left) hide)
    )
    (property "Datasheet" "https://www.bourns.com/docs/product-datasheets/cr.pdf" (id 3) (at 202.692 199.009 0)
      (effects (font (size 1.27 1.27)) hide)
    )
    (property "Manufacturer" "Bourns" (id 4) (at 212.852 204.089 0)
      (effects (font (size 1.524 1.524)) (justify left) hide)
    )
    (property "MPN" "CR0402-FX-1003GLF" (id 5) (at 210.312 204.089 0)
      (effects (font (size 1.524 1.524)) (justify left) hide)
    )
    (property "Val" "100k" (id 6) (at 205.232 203.4539 90)
      (effects (font (size 1.27 1.27)) (justify left))
    )
    (property "License" "Apache-2.0" (id 7) (at 177.292 219.329 0)
      (effects (font (size 1.27 1.27) (thickness 0.15)) (justify left bottom) hide)
    )
    (property "Author" "Antmicro" (id 8) (at 174.752 219.329 0)
      (effects (font (size 1.27 1.27) (thickness 0.15)) (justify left bottom) hide)
    )
    (property "Tolerance" "1%" (id 9) (at 192.532 219.329 0)
      (effects (font (size 1.27 1.27)) (justify left bottom) hide)
    )
    (pin "1")
    (pin "2")
  )

  (symbol (lib_id "sa800u-baseboard-hw:R_4k7_0402") (at 251.46 64.008 90) (unit 1)
    (in_bom yes) (on_board yes)
    (property "Reference" "R167" (id 0) (at 252.476 58.42 90)
      (effects (font (size 1.524 1.524)) (justify right))
    )
    (property "Value" "R_4k7_0402" (id 1) (at 255.27 64.008 0)
      (effects (font (size 1.524 1.524)) hide)
    )
    (property "Footprint" "sa800u-baseboard-hw-footprints:R_0402_1005Metric" (id 2) (at 246.38 58.928 0)
      (effects (font (size 1.524 1.524)) (justify left) hide)
    )
    (property "Datasheet" "https://www.bourns.com/docs/product-datasheets/cr.pdf" (id 3) (at 251.46 64.008 0)
      (effects (font (size 1.27 1.27)) hide)
    )
    (property "Manufacturer" "Bourns" (id 4) (at 241.3 58.928 0)
      (effects (font (size 1.524 1.524)) (justify left) hide)
    )
    (property "MPN" "CR0402-FX-4701GLF" (id 5) (at 243.84 58.928 0)
      (effects (font (size 1.524 1.524)) (justify left) hide)
    )
    (property "Val" "4k7" (id 6) (at 253.238 61.468 90)
      (effects (font (size 1.27 1.27)) (justify right))
    )
    (property "License" "Apache-2.0" (id 7) (at 276.86 43.688 0)
      (effects (font (size 1.27 1.27) (thickness 0.15)) (justify left bottom) hide)
    )
    (property "Author" "Antmicro" (id 8) (at 279.4 43.688 0)
      (effects (font (size 1.27 1.27) (thickness 0.15)) (justify left bottom) hide)
    )
    (property "Tolerance" "1%" (id 9) (at 261.62 43.688 0)
      (effects (font (size 1.27 1.27)) (justify left bottom) hide)
    )
    (pin "1")
    (pin "2")
  )

  (symbol (lib_id "sa800u-baseboard-hw:R_4k7_0402") (at 259.715 64.008 90) (unit 1)
    (in_bom yes) (on_board yes)
    (property "Reference" "R168" (id 0) (at 260.096 58.42 90)
      (effects (font (size 1.524 1.524)) (justify right))
    )
    (property "Value" "R_4k7_0402" (id 1) (at 263.525 64.008 0)
      (effects (font (size 1.524 1.524)) hide)
    )
    (property "Footprint" "sa800u-baseboard-hw-footprints:R_0402_1005Metric" (id 2) (at 254.635 58.928 0)
      (effects (font (size 1.524 1.524)) (justify left) hide)
    )
    (property "Datasheet" "https://www.bourns.com/docs/product-datasheets/cr.pdf" (id 3) (at 259.715 64.008 0)
      (effects (font (size 1.27 1.27)) hide)
    )
    (property "Manufacturer" "Bourns" (id 4) (at 249.555 58.928 0)
      (effects (font (size 1.524 1.524)) (justify left) hide)
    )
    (property "MPN" "CR0402-FX-4701GLF" (id 5) (at 252.095 58.928 0)
      (effects (font (size 1.524 1.524)) (justify left) hide)
    )
    (property "Val" "4k7" (id 6) (at 260.858 61.468 90)
      (effects (font (size 1.27 1.27)) (justify right))
    )
    (property "License" "Apache-2.0" (id 7) (at 285.115 43.688 0)
      (effects (font (size 1.27 1.27) (thickness 0.15)) (justify left bottom) hide)
    )
    (property "Author" "Antmicro" (id 8) (at 287.655 43.688 0)
      (effects (font (size 1.27 1.27) (thickness 0.15)) (justify left bottom) hide)
    )
    (property "Tolerance" "1%" (id 9) (at 269.875 43.688 0)
      (effects (font (size 1.27 1.27)) (justify left bottom) hide)
    )
    (pin "1")
    (pin "2")
  )

  (symbol (lib_id "sa800u-baseboard-hw:R_4k7_0402") (at 267.97 64.008 90) (unit 1)
    (in_bom yes) (on_board yes)
    (property "Reference" "R170" (id 0) (at 268.986 58.42 90)
      (effects (font (size 1.524 1.524)) (justify right))
    )
    (property "Value" "R_4k7_0402" (id 1) (at 271.78 64.008 0)
      (effects (font (size 1.524 1.524)) hide)
    )
    (property "Footprint" "sa800u-baseboard-hw-footprints:R_0402_1005Metric" (id 2) (at 262.89 58.928 0)
      (effects (font (size 1.524 1.524)) (justify left) hide)
    )
    (property "Datasheet" "https://www.bourns.com/docs/product-datasheets/cr.pdf" (id 3) (at 267.97 64.008 0)
      (effects (font (size 1.27 1.27)) hide)
    )
    (property "Manufacturer" "Bourns" (id 4) (at 257.81 58.928 0)
      (effects (font (size 1.524 1.524)) (justify left) hide)
    )
    (property "MPN" "CR0402-FX-4701GLF" (id 5) (at 260.35 58.928 0)
      (effects (font (size 1.524 1.524)) (justify left) hide)
    )
    (property "Val" "4k7" (id 6) (at 269.748 61.468 90)
      (effects (font (size 1.27 1.27)) (justify right))
    )
    (property "License" "Apache-2.0" (id 7) (at 293.37 43.688 0)
      (effects (font (size 1.27 1.27) (thickness 0.15)) (justify left bottom) hide)
    )
    (property "Author" "Antmicro" (id 8) (at 295.91 43.688 0)
      (effects (font (size 1.27 1.27) (thickness 0.15)) (justify left bottom) hide)
    )
    (property "Tolerance" "1%" (id 9) (at 278.13 43.688 0)
      (effects (font (size 1.27 1.27)) (justify left bottom) hide)
    )
    (pin "1")
    (pin "2")
  )

  (symbol (lib_id "sa800u-baseboard-hw:ASMB-TTF0-0A20B") (at 287.02 157.353 270) (unit 1)
    (in_bom yes) (on_board yes) (fields_autoplaced)
    (property "Reference" "D36" (id 0) (at 292.1 163.703 90)
      (effects (font (size 1.524 1.524)) (justify left))
    )
    (property "Value" "ASMB-TTF0-0A20B" (id 1) (at 292.1 167.513 90)
      (effects (font (size 1.524 1.524)) (justify left))
    )
    (property "Footprint" "sa800u-baseboard-hw-footprints:PLCC6_3.5x3.7mm" (id 2) (at 269.24 147.193 0)
      (effects (font (size 1.524 1.524)) (justify left) hide)
    )
    (property "Datasheet" "https://docs.broadcom.com/doc/ASMB-TTF0-0A20B-DS101" (id 3) (at 294.64 162.433 0)
      (effects (font (size 1.524 1.524)) (justify left) hide)
    )
    (property "MPN" "ASMB-TTF0-0A20B" (id 4) (at 271.78 145.923 0)
      (effects (font (size 1.524 1.524)) (justify left) hide)
    )
    (property "Manufacturer" "Broadcom" (id 5) (at 274.32 153.543 0)
      (effects (font (size 1.524 1.524)) (justify left) hide)
    )
    (property "Author" "Antmicro" (id 6) (at 269.24 185.293 0)
      (effects (font (size 1.27 1.27) (thickness 0.15)) (justify left bottom) hide)
    )
    (property "License" "Apache-2.0" (id 7) (at 266.7 185.293 0)
      (effects (font (size 1.27 1.27) (thickness 0.15)) (justify left bottom) hide)
    )
    (pin "1")
    (pin "2")
    (pin "3")
    (pin "4")
    (pin "5")
    (pin "6")
  )

  (symbol (lib_id "sa800u-baseboard-hw:TP_0.75mm_SMD") (at 278.003 66.04 0) (unit 1)
    (in_bom yes) (on_board yes) (fields_autoplaced)
    (property "Reference" "TP89" (id 0) (at 283.337 66.0399 0)
      (effects (font (size 1.27 1.27)) (justify left))
    )
    (property "Value" "TP_0.75mm_SMD" (id 1) (at 278.003 68.58 0)
      (effects (font (size 1.27 1.27)) hide)
    )
    (property "Footprint" "sa800u-baseboard-hw-footprints:TP_SMD_0.75mm" (id 2) (at 283.083 60.96 0)
      (effects (font (size 1.524 1.524)) (justify left) hide)
    )
    (property "Datasheet" "" (id 3) (at 283.083 58.42 0)
      (effects (font (size 1.524 1.524)) (justify left) hide)
    )
    (property "MPN" "" (id 4) (at 295.783 81.28 0)
      (effects (font (size 1.27 1.27) (thickness 0.15)) (justify left bottom) hide)
    )
    (property "Manufacturer" "" (id 5) (at 295.783 83.82 0)
      (effects (font (size 1.27 1.27) (thickness 0.15)) (justify left bottom) hide)
    )
    (property "Author" "Antmicro" (id 6) (at 295.783 86.36 0)
      (effects (font (size 1.27 1.27) (thickness 0.15)) (justify left bottom) hide)
    )
    (property "License" "Apache-2.0" (id 7) (at 295.783 88.9 0)
      (effects (font (size 1.27 1.27) (thickness 0.15)) (justify left bottom) hide)
    )
    (pin "1")
  )

  (symbol (lib_id "sa800u-baseboard-hw:GND") (at 287.02 184.15 0) (unit 1)
    (in_bom yes) (on_board yes) (fields_autoplaced)
    (property "Reference" "#PWR0268" (id 0) (at 287.02 190.5 0)
      (effects (font (size 1.27 1.27)) hide)
    )
    (property "Value" "GND" (id 1) (at 287.02 189.23 0))
    (property "Footprint" "" (id 2) (at 287.02 184.15 0)
      (effects (font (size 1.27 1.27)) hide)
    )
    (property "Datasheet" "" (id 3) (at 287.02 184.15 0)
      (effects (font (size 1.27 1.27)) hide)
    )
    (property "Author" "Antmicro" (id 4) (at 295.91 191.77 0)
      (effects (font (size 1.27 1.27) (thickness 0.15)) (justify left bottom) hide)
    )
    (property "License" "Apache-2.0" (id 5) (at 295.91 194.31 0)
      (effects (font (size 1.27 1.27) (thickness 0.15)) (justify left bottom) hide)
    )
    (pin "1")
  )

  (symbol (lib_id "sa800u-baseboard-hw:TP_0.75mm_SMD") (at 278.003 68.58 0) (unit 1)
    (in_bom yes) (on_board yes) (fields_autoplaced)
    (property "Reference" "TP91" (id 0) (at 283.21 68.5799 0)
      (effects (font (size 1.27 1.27)) (justify left))
    )
    (property "Value" "TP_0.75mm_SMD" (id 1) (at 278.003 71.12 0)
      (effects (font (size 1.27 1.27)) hide)
    )
    (property "Footprint" "sa800u-baseboard-hw-footprints:TP_SMD_0.75mm" (id 2) (at 283.083 63.5 0)
      (effects (font (size 1.524 1.524)) (justify left) hide)
    )
    (property "Datasheet" "" (id 3) (at 283.083 60.96 0)
      (effects (font (size 1.524 1.524)) (justify left) hide)
    )
    (property "MPN" "" (id 4) (at 295.783 83.82 0)
      (effects (font (size 1.27 1.27) (thickness 0.15)) (justify left bottom) hide)
    )
    (property "Manufacturer" "" (id 5) (at 295.783 86.36 0)
      (effects (font (size 1.27 1.27) (thickness 0.15)) (justify left bottom) hide)
    )
    (property "Author" "Antmicro" (id 6) (at 295.783 88.9 0)
      (effects (font (size 1.27 1.27) (thickness 0.15)) (justify left bottom) hide)
    )
    (property "License" "Apache-2.0" (id 7) (at 295.783 91.44 0)
      (effects (font (size 1.27 1.27) (thickness 0.15)) (justify left bottom) hide)
    )
    (pin "1")
  )

  (symbol (lib_id "sa800u-baseboard-hw:TP_0.75mm_SMD") (at 278.13 71.12 0) (unit 1)
    (in_bom yes) (on_board yes) (fields_autoplaced)
    (property "Reference" "TP95" (id 0) (at 283.337 71.1199 0)
      (effects (font (size 1.27 1.27)) (justify left))
    )
    (property "Value" "TP_0.75mm_SMD" (id 1) (at 278.13 73.66 0)
      (effects (font (size 1.27 1.27)) hide)
    )
    (property "Footprint" "sa800u-baseboard-hw-footprints:TP_SMD_0.75mm" (id 2) (at 283.21 66.04 0)
      (effects (font (size 1.524 1.524)) (justify left) hide)
    )
    (property "Datasheet" "" (id 3) (at 283.21 63.5 0)
      (effects (font (size 1.524 1.524)) (justify left) hide)
    )
    (property "MPN" "" (id 4) (at 295.91 86.36 0)
      (effects (font (size 1.27 1.27) (thickness 0.15)) (justify left bottom) hide)
    )
    (property "Manufacturer" "" (id 5) (at 295.91 88.9 0)
      (effects (font (size 1.27 1.27) (thickness 0.15)) (justify left bottom) hide)
    )
    (property "Author" "Antmicro" (id 6) (at 295.91 91.44 0)
      (effects (font (size 1.27 1.27) (thickness 0.15)) (justify left bottom) hide)
    )
    (property "License" "Apache-2.0" (id 7) (at 295.91 93.98 0)
      (effects (font (size 1.27 1.27) (thickness 0.15)) (justify left bottom) hide)
    )
    (pin "1")
  )

  (symbol (lib_id "sa800u-baseboard-hw:TP_0.75mm_SMD") (at 278.003 73.66 0) (unit 1)
    (in_bom yes) (on_board yes) (fields_autoplaced)
    (property "Reference" "TP96" (id 0) (at 283.21 73.6599 0)
      (effects (font (size 1.27 1.27)) (justify left))
    )
    (property "Value" "TP_0.75mm_SMD" (id 1) (at 278.003 76.2 0)
      (effects (font (size 1.27 1.27)) hide)
    )
    (property "Footprint" "sa800u-baseboard-hw-footprints:TP_SMD_0.75mm" (id 2) (at 283.083 68.58 0)
      (effects (font (size 1.524 1.524)) (justify left) hide)
    )
    (property "Datasheet" "" (id 3) (at 283.083 66.04 0)
      (effects (font (size 1.524 1.524)) (justify left) hide)
    )
    (property "MPN" "" (id 4) (at 295.783 88.9 0)
      (effects (font (size 1.27 1.27) (thickness 0.15)) (justify left bottom) hide)
    )
    (property "Manufacturer" "" (id 5) (at 295.783 91.44 0)
      (effects (font (size 1.27 1.27) (thickness 0.15)) (justify left bottom) hide)
    )
    (property "Author" "Antmicro" (id 6) (at 295.783 93.98 0)
      (effects (font (size 1.27 1.27) (thickness 0.15)) (justify left bottom) hide)
    )
    (property "License" "Apache-2.0" (id 7) (at 295.783 96.52 0)
      (effects (font (size 1.27 1.27) (thickness 0.15)) (justify left bottom) hide)
    )
    (pin "1")
  )

  (symbol (lib_id "sa800u-baseboard-hw:SQS401EN-T1_BE3") (at 238.76 134.62 270) (mirror x) (unit 1)
    (in_bom yes) (on_board yes) (fields_autoplaced)
    (property "Reference" "Q17" (id 0) (at 241.3 120.65 90)
      (effects (font (size 1.524 1.524)))
    )
    (property "Value" "SQS401EN-T1_BE3" (id 1) (at 241.3 124.46 90)
      (effects (font (size 1.524 1.524)))
    )
    (property "Footprint" "sa800u-baseboard-hw-footprints:Vishay_PowerPAK_1212-8_Single" (id 2) (at 243.84 129.54 0)
      (effects (font (size 1.524 1.524)) (justify left) hide)
    )
    (property "Datasheet" "https://www.vishay.com/docs/65529/sqs401en.pdf" (id 3) (at 246.38 129.54 0)
      (effects (font (size 1.524 1.524)) (justify left) hide)
    )
    (property "MPN" "SQS401EN-T1_BE3" (id 4) (at 251.46 129.54 0)
      (effects (font (size 1.524 1.524)) (justify left) hide)
    )
    (property "Manufacturer" "Vishay" (id 5) (at 266.7 129.54 0)
      (effects (font (size 1.524 1.524)) (justify left) hide)
    )
    (property "Author" "Antmicro" (id 6) (at 218.44 119.38 0)
      (effects (font (size 1.27 1.27) (thickness 0.15)) (justify left bottom) hide)
    )
    (property "License" "Apache-2.0" (id 7) (at 215.9 119.38 0)
      (effects (font (size 1.27 1.27) (thickness 0.15)) (justify left bottom) hide)
    )
    (pin "1")
    (pin "2")
    (pin "3")
    (pin "4")
    (pin "5")
  )

  (symbol (lib_id "sa800u-baseboard-hw:12401598E4_2A") (at 83.82 132.08 0) (mirror y) (unit 1)
    (in_bom yes) (on_board yes) (fields_autoplaced)
    (property "Reference" "J11" (id 0) (at 72.4535 119.38 0))
    (property "Value" "12401598E4_2A" (id 1) (at 72.4535 121.92 0))
    (property "Footprint" "sa800u-baseboard-hw-footprints:USB-C_12401610E4_2A" (id 2) (at 78.74 127 0)
      (effects (font (size 1.524 1.524)) (justify left) hide)
    )
    (property "Datasheet" "http://www.amphenol-icc.com/media/wysiwyg/files/drawing/12401598xxx2a.pdf" (id 3) (at 78.74 124.46 0)
      (effects (font (size 1.524 1.524)) (justify left) hide)
    )
    (property "MPN" "12401598E4#2A" (id 4) (at 78.74 119.38 0)
      (effects (font (size 1.524 1.524)) (justify left) hide)
    )
    (property "Manufacturer" "Amphenol" (id 5) (at 78.74 104.14 0)
      (effects (font (size 1.524 1.524)) (justify left) hide)
    )
    (property "Author" "Antmicro" (id 6) (at 50.8 149.86 0)
      (effects (font (size 1.27 1.27) (thickness 0.15)) (justify left bottom) hide)
    )
    (property "License" "Apache-2.0" (id 7) (at 50.8 152.4 0)
      (effects (font (size 1.27 1.27) (thickness 0.15)) (justify left bottom) hide)
    )
    (pin "A1")
    (pin "A10")
    (pin "A11")
    (pin "A12")
    (pin "A2")
    (pin "A3")
    (pin "A4")
    (pin "A5")
    (pin "A6")
    (pin "A7")
    (pin "A8")
    (pin "A9")
    (pin "B1")
    (pin "B10")
    (pin "B11")
    (pin "B12")
    (pin "B2")
    (pin "B3")
    (pin "B4")
    (pin "B5")
    (pin "B6")
    (pin "B7")
    (pin "B8")
    (pin "B9")
    (pin "SH")
  )

  (symbol (lib_id "sa800u-baseboard-hw:R_0R_0402") (at 224.917 68.58 0) (unit 1)
    (in_bom yes) (on_board yes)
    (property "Reference" "R163" (id 0) (at 222.504 67.437 0)
      (effects (font (size 1.524 1.524)))
    )
    (property "Value" "R_0R_0402" (id 1) (at 224.917 72.39 0)
      (effects (font (size 1.524 1.524)) hide)
    )
    (property "Footprint" "sa800u-baseboard-hw-footprints:R_0402_1005Metric" (id 2) (at 229.997 63.5 0)
      (effects (font (size 1.524 1.524)) (justify left) hide)
    )
    (property "Datasheet" "https://industrial.panasonic.com/cdbs/www-data/pdf/RDA0000/AOA0000C301.pdf" (id 3) (at 224.917 68.58 0)
      (effects (font (size 1.27 1.27)) hide)
    )
    (property "Manufacturer" "Panasonic" (id 4) (at 229.997 58.42 0)
      (effects (font (size 1.524 1.524)) (justify left) hide)
    )
    (property "MPN" "ERJ2GE0R00X" (id 5) (at 229.997 60.96 0)
      (effects (font (size 1.524 1.524)) (justify left) hide)
    )
    (property "Val" "0R" (id 6) (at 230.759 67.564 0))
    (property "License" "Apache-2.0" (id 7) (at 245.237 93.98 0)
      (effects (font (size 1.27 1.27) (thickness 0.15)) (justify left bottom) hide)
    )
    (property "Author" "Antmicro" (id 8) (at 245.237 96.52 0)
      (effects (font (size 1.27 1.27) (thickness 0.15)) (justify left bottom) hide)
    )
    (property "Tolerance" "~" (id 9) (at 245.237 78.74 0)
      (effects (font (size 1.27 1.27)) (justify left bottom) hide)
    )
    (property "Current" "1A" (id 10) (at 245.237 99.06 0)
      (effects (font (size 1.27 1.27) (thickness 0.15)) (justify left bottom) hide)
    )
    (pin "1")
    (pin "2")
  )

  (symbol (lib_id "sa800u-baseboard-hw:R_0R_0402") (at 224.917 66.04 0) (unit 1)
    (in_bom yes) (on_board yes)
    (property "Reference" "R162" (id 0) (at 222.504 65.024 0)
      (effects (font (size 1.524 1.524)))
    )
    (property "Value" "R_0R_0402" (id 1) (at 224.917 69.85 0)
      (effects (font (size 1.524 1.524)) hide)
    )
    (property "Footprint" "sa800u-baseboard-hw-footprints:R_0402_1005Metric" (id 2) (at 229.997 60.96 0)
      (effects (font (size 1.524 1.524)) (justify left) hide)
    )
    (property "Datasheet" "https://industrial.panasonic.com/cdbs/www-data/pdf/RDA0000/AOA0000C301.pdf" (id 3) (at 224.917 66.04 0)
      (effects (font (size 1.27 1.27)) hide)
    )
    (property "Manufacturer" "Panasonic" (id 4) (at 229.997 55.88 0)
      (effects (font (size 1.524 1.524)) (justify left) hide)
    )
    (property "MPN" "ERJ2GE0R00X" (id 5) (at 229.997 58.42 0)
      (effects (font (size 1.524 1.524)) (justify left) hide)
    )
    (property "Val" "0R" (id 6) (at 230.886 65.024 0))
    (property "License" "Apache-2.0" (id 7) (at 245.237 91.44 0)
      (effects (font (size 1.27 1.27) (thickness 0.15)) (justify left bottom) hide)
    )
    (property "Author" "Antmicro" (id 8) (at 245.237 93.98 0)
      (effects (font (size 1.27 1.27) (thickness 0.15)) (justify left bottom) hide)
    )
    (property "Tolerance" "~" (id 9) (at 245.237 76.2 0)
      (effects (font (size 1.27 1.27)) (justify left bottom) hide)
    )
    (property "Current" "1A" (id 10) (at 245.237 96.52 0)
      (effects (font (size 1.27 1.27) (thickness 0.15)) (justify left bottom) hide)
    )
    (pin "1")
    (pin "2")
  )

  (symbol (lib_id "sa800u-baseboard-hw:R_0R_0402") (at 224.917 73.66 0) (unit 1)
    (in_bom yes) (on_board yes)
    (property "Reference" "R165" (id 0) (at 222.504 72.644 0)
      (effects (font (size 1.524 1.524)))
    )
    (property "Value" "R_0R_0402" (id 1) (at 224.917 77.47 0)
      (effects (font (size 1.524 1.524)) hide)
    )
    (property "Footprint" "sa800u-baseboard-hw-footprints:R_0402_1005Metric" (id 2) (at 229.997 68.58 0)
      (effects (font (size 1.524 1.524)) (justify left) hide)
    )
    (property "Datasheet" "https://industrial.panasonic.com/cdbs/www-data/pdf/RDA0000/AOA0000C301.pdf" (id 3) (at 224.917 73.66 0)
      (effects (font (size 1.27 1.27)) hide)
    )
    (property "Manufacturer" "Panasonic" (id 4) (at 229.997 63.5 0)
      (effects (font (size 1.524 1.524)) (justify left) hide)
    )
    (property "MPN" "ERJ2GE0R00X" (id 5) (at 229.997 66.04 0)
      (effects (font (size 1.524 1.524)) (justify left) hide)
    )
    (property "Val" "0R" (id 6) (at 231.013 72.771 0))
    (property "License" "Apache-2.0" (id 7) (at 245.237 99.06 0)
      (effects (font (size 1.27 1.27) (thickness 0.15)) (justify left bottom) hide)
    )
    (property "Author" "Antmicro" (id 8) (at 245.237 101.6 0)
      (effects (font (size 1.27 1.27) (thickness 0.15)) (justify left bottom) hide)
    )
    (property "Tolerance" "~" (id 9) (at 245.237 83.82 0)
      (effects (font (size 1.27 1.27)) (justify left bottom) hide)
    )
    (property "Current" "1A" (id 10) (at 245.237 104.14 0)
      (effects (font (size 1.27 1.27) (thickness 0.15)) (justify left bottom) hide)
    )
    (pin "1")
    (pin "2")
  )

  (symbol (lib_id "sa800u-baseboard-hw:R_0R_0402") (at 224.917 71.12 0) (unit 1)
    (in_bom yes) (on_board yes)
    (property "Reference" "R164" (id 0) (at 222.504 69.977 0)
      (effects (font (size 1.524 1.524)))
    )
    (property "Value" "R_0R_0402" (id 1) (at 224.917 74.93 0)
      (effects (font (size 1.524 1.524)) hide)
    )
    (property "Footprint" "sa800u-baseboard-hw-footprints:R_0402_1005Metric" (id 2) (at 229.997 66.04 0)
      (effects (font (size 1.524 1.524)) (justify left) hide)
    )
    (property "Datasheet" "https://industrial.panasonic.com/cdbs/www-data/pdf/RDA0000/AOA0000C301.pdf" (id 3) (at 224.917 71.12 0)
      (effects (font (size 1.27 1.27)) hide)
    )
    (property "Manufacturer" "Panasonic" (id 4) (at 229.997 60.96 0)
      (effects (font (size 1.524 1.524)) (justify left) hide)
    )
    (property "MPN" "ERJ2GE0R00X" (id 5) (at 229.997 63.5 0)
      (effects (font (size 1.524 1.524)) (justify left) hide)
    )
    (property "Val" "0R" (id 6) (at 230.759 70.104 0))
    (property "License" "Apache-2.0" (id 7) (at 245.237 96.52 0)
      (effects (font (size 1.27 1.27) (thickness 0.15)) (justify left bottom) hide)
    )
    (property "Author" "Antmicro" (id 8) (at 245.237 99.06 0)
      (effects (font (size 1.27 1.27) (thickness 0.15)) (justify left bottom) hide)
    )
    (property "Tolerance" "~" (id 9) (at 245.237 81.28 0)
      (effects (font (size 1.27 1.27)) (justify left bottom) hide)
    )
    (property "Current" "1A" (id 10) (at 245.237 101.6 0)
      (effects (font (size 1.27 1.27) (thickness 0.15)) (justify left bottom) hide)
    )
    (pin "1")
    (pin "2")
  )

  (symbol (lib_id "sa800u-baseboard-hw:PESD18VF1BSFYL") (at 307.34 135.89 270) (unit 1)
    (in_bom yes) (on_board yes) (fields_autoplaced)
    (property "Reference" "D37" (id 0) (at 309.88 134.9375 90)
      (effects (font (size 1.524 1.524)) (justify left))
    )
    (property "Value" "PESD18VF1BSFYL" (id 1) (at 309.88 138.7475 90)
      (effects (font (size 1.524 1.524)) (justify left))
    )
    (property "Footprint" "sa800u-baseboard-hw-footprints:D_0201_0603Metric" (id 2) (at 295.91 135.89 0)
      (effects (font (size 2.54 2.54)) (justify left) hide)
    )
    (property "Datasheet" "https://www.mouser.pl/datasheet/2/916/PESD18VF1BSF-1599696.pdf" (id 3) (at 303.53 141.224 0)
      (effects (font (size 2.54 2.54)) hide)
    )
    (property "Manufacturer" "Nexperia" (id 4) (at 292.735 135.89 0)
      (effects (font (size 2.54 2.54)) (justify left) hide)
    )
    (property "MPN" "PESD18VF1BSFYL" (id 5) (at 299.085 135.89 0)
      (effects (font (size 2.54 2.54)) (justify left) hide)
    )
    (property "Author" "Antmicro" (id 6) (at 287.02 161.29 0)
      (effects (font (size 1.27 1.27) (thickness 0.15)) (justify left bottom) hide)
    )
    (property "License" "Apache-2.0" (id 7) (at 284.48 161.29 0)
      (effects (font (size 1.27 1.27) (thickness 0.15)) (justify left bottom) hide)
    )
    (pin "1")
    (pin "2")
  )

  (symbol (lib_id "sa800u-baseboard-hw:GND") (at 77.47 171.45 0) (unit 1)
    (in_bom yes) (on_board yes) (fields_autoplaced)
    (property "Reference" "#PWR0253" (id 0) (at 77.47 177.8 0)
      (effects (font (size 1.27 1.27)) hide)
    )
    (property "Value" "GND" (id 1) (at 77.47 176.53 0))
    (property "Footprint" "" (id 2) (at 77.47 171.45 0)
      (effects (font (size 1.27 1.27)) hide)
    )
    (property "Datasheet" "" (id 3) (at 77.47 171.45 0)
      (effects (font (size 1.27 1.27)) hide)
    )
    (property "Author" "Antmicro" (id 4) (at 86.36 179.07 0)
      (effects (font (size 1.27 1.27) (thickness 0.15)) (justify left bottom) hide)
    )
    (property "License" "Apache-2.0" (id 5) (at 86.36 181.61 0)
      (effects (font (size 1.27 1.27) (thickness 0.15)) (justify left bottom) hide)
    )
    (pin "1")
  )

  (symbol (lib_id "sa800u-baseboard-hw:GND") (at 162.941 207.391 0) (unit 1)
    (in_bom yes) (on_board yes) (fields_autoplaced)
    (property "Reference" "#PWR0257" (id 0) (at 162.941 213.741 0)
      (effects (font (size 1.27 1.27)) hide)
    )
    (property "Value" "GND" (id 1) (at 162.941 211.836 0))
    (property "Footprint" "" (id 2) (at 162.941 207.391 0)
      (effects (font (size 1.27 1.27)) hide)
    )
    (property "Datasheet" "" (id 3) (at 162.941 207.391 0)
      (effects (font (size 1.27 1.27)) hide)
    )
    (property "Author" "Antmicro" (id 4) (at 171.831 215.011 0)
      (effects (font (size 1.27 1.27) (thickness 0.15)) (justify left bottom) hide)
    )
    (property "License" "Apache-2.0" (id 5) (at 171.831 217.551 0)
      (effects (font (size 1.27 1.27) (thickness 0.15)) (justify left bottom) hide)
    )
    (pin "1")
  )

  (symbol (lib_id "sa800u-baseboard-hw:PESD18VF1BSFYL") (at 162.941 195.961 270) (unit 1)
    (in_bom yes) (on_board yes) (fields_autoplaced)
    (property "Reference" "D34" (id 0) (at 166.751 200.406 90)
      (effects (font (size 1.524 1.524)) (justify left))
    )
    (property "Value" "PESD18VF1BSFYL" (id 1) (at 166.751 204.216 90)
      (effects (font (size 1.524 1.524)) (justify left))
    )
    (property "Footprint" "sa800u-baseboard-hw-footprints:D_0201_0603Metric" (id 2) (at 151.511 195.961 0)
      (effects (font (size 2.54 2.54)) (justify left) hide)
    )
    (property "Datasheet" "https://www.mouser.pl/datasheet/2/916/PESD18VF1BSF-1599696.pdf" (id 3) (at 159.131 201.295 0)
      (effects (font (size 2.54 2.54)) hide)
    )
    (property "Manufacturer" "Nexperia" (id 4) (at 148.336 195.961 0)
      (effects (font (size 2.54 2.54)) (justify left) hide)
    )
    (property "MPN" "PESD18VF1BSFYL" (id 5) (at 154.686 195.961 0)
      (effects (font (size 2.54 2.54)) (justify left) hide)
    )
    (property "Author" "Antmicro" (id 6) (at 142.621 221.361 0)
      (effects (font (size 1.27 1.27) (thickness 0.15)) (justify left bottom) hide)
    )
    (property "License" "Apache-2.0" (id 7) (at 140.081 221.361 0)
      (effects (font (size 1.27 1.27) (thickness 0.15)) (justify left bottom) hide)
    )
    (pin "1")
    (pin "2")
  )

  (symbol (lib_id "sa800u-baseboard-hw:GND") (at 157.861 207.391 0) (unit 1)
    (in_bom yes) (on_board yes) (fields_autoplaced)
    (property "Reference" "#PWR0256" (id 0) (at 157.861 213.741 0)
      (effects (font (size 1.27 1.27)) hide)
    )
    (property "Value" "GND" (id 1) (at 157.861 212.471 0))
    (property "Footprint" "" (id 2) (at 157.861 207.391 0)
      (effects (font (size 1.27 1.27)) hide)
    )
    (property "Datasheet" "" (id 3) (at 157.861 207.391 0)
      (effects (font (size 1.27 1.27)) hide)
    )
    (property "Author" "Antmicro" (id 4) (at 166.751 215.011 0)
      (effects (font (size 1.27 1.27) (thickness 0.15)) (justify left bottom) hide)
    )
    (property "License" "Apache-2.0" (id 5) (at 166.751 217.551 0)
      (effects (font (size 1.27 1.27) (thickness 0.15)) (justify left bottom) hide)
    )
    (pin "1")
  )

  (symbol (lib_id "sa800u-baseboard-hw:PESD18VF1BSFYL") (at 157.861 195.961 270) (unit 1)
    (in_bom yes) (on_board yes) (fields_autoplaced)
    (property "Reference" "D33" (id 0) (at 154.051 200.406 90)
      (effects (font (size 1.524 1.524)) (justify right))
    )
    (property "Value" "PESD18VF1BSFYL" (id 1) (at 154.051 204.216 90)
      (effects (font (size 1.524 1.524)) (justify right))
    )
    (property "Footprint" "sa800u-baseboard-hw-footprints:D_0201_0603Metric" (id 2) (at 146.431 195.961 0)
      (effects (font (size 2.54 2.54)) (justify left) hide)
    )
    (property "Datasheet" "https://www.mouser.pl/datasheet/2/916/PESD18VF1BSF-1599696.pdf" (id 3) (at 154.051 201.295 0)
      (effects (font (size 2.54 2.54)) hide)
    )
    (property "Manufacturer" "Nexperia" (id 4) (at 143.256 195.961 0)
      (effects (font (size 2.54 2.54)) (justify left) hide)
    )
    (property "MPN" "PESD18VF1BSFYL" (id 5) (at 149.606 195.961 0)
      (effects (font (size 2.54 2.54)) (justify left) hide)
    )
    (property "Author" "Antmicro" (id 6) (at 137.541 221.361 0)
      (effects (font (size 1.27 1.27) (thickness 0.15)) (justify left bottom) hide)
    )
    (property "License" "Apache-2.0" (id 7) (at 135.001 221.361 0)
      (effects (font (size 1.27 1.27) (thickness 0.15)) (justify left bottom) hide)
    )
    (pin "1")
    (pin "2")
  )

  (symbol (lib_id "sa800u-baseboard-hw:GND") (at 241.681 201.676 0) (unit 1)
    (in_bom yes) (on_board yes) (fields_autoplaced)
    (property "Reference" "#PWR0264" (id 0) (at 241.681 208.026 0)
      (effects (font (size 1.27 1.27)) hide)
    )
    (property "Value" "GND" (id 1) (at 241.681 206.756 0))
    (property "Footprint" "" (id 2) (at 241.681 201.676 0)
      (effects (font (size 1.27 1.27)) hide)
    )
    (property "Datasheet" "" (id 3) (at 241.681 201.676 0)
      (effects (font (size 1.27 1.27)) hide)
    )
    (property "Author" "Antmicro" (id 4) (at 250.571 209.296 0)
      (effects (font (size 1.27 1.27) (thickness 0.15)) (justify left bottom) hide)
    )
    (property "License" "Apache-2.0" (id 5) (at 250.571 211.836 0)
      (effects (font (size 1.27 1.27) (thickness 0.15)) (justify left bottom) hide)
    )
    (pin "1")
  )

  (symbol (lib_id "sa800u-baseboard-hw:GND") (at 247.65 197.739 0) (unit 1)
    (in_bom yes) (on_board yes) (fields_autoplaced)
    (property "Reference" "#PWR0265" (id 0) (at 247.65 204.089 0)
      (effects (font (size 1.27 1.27)) hide)
    )
    (property "Value" "GND" (id 1) (at 247.65 202.819 0))
    (property "Footprint" "" (id 2) (at 247.65 197.739 0)
      (effects (font (size 1.27 1.27)) hide)
    )
    (property "Datasheet" "" (id 3) (at 247.65 197.739 0)
      (effects (font (size 1.27 1.27)) hide)
    )
    (property "Author" "Antmicro" (id 4) (at 256.54 205.359 0)
      (effects (font (size 1.27 1.27) (thickness 0.15)) (justify left bottom) hide)
    )
    (property "License" "Apache-2.0" (id 5) (at 256.54 207.899 0)
      (effects (font (size 1.27 1.27) (thickness 0.15)) (justify left bottom) hide)
    )
    (pin "1")
  )

  (symbol (lib_id "sa800u-baseboard-hw:GND") (at 259.715 197.866 0) (unit 1)
    (in_bom yes) (on_board yes) (fields_autoplaced)
    (property "Reference" "#PWR0266" (id 0) (at 259.715 204.216 0)
      (effects (font (size 1.27 1.27)) hide)
    )
    (property "Value" "GND" (id 1) (at 261.62 199.1359 0)
      (effects (font (size 1.27 1.27)) (justify left))
    )
    (property "Footprint" "" (id 2) (at 259.715 197.866 0)
      (effects (font (size 1.27 1.27)) hide)
    )
    (property "Datasheet" "" (id 3) (at 259.715 197.866 0)
      (effects (font (size 1.27 1.27)) hide)
    )
    (property "Author" "Antmicro" (id 4) (at 268.605 205.486 0)
      (effects (font (size 1.27 1.27) (thickness 0.15)) (justify left bottom) hide)
    )
    (property "License" "Apache-2.0" (id 5) (at 268.605 208.026 0)
      (effects (font (size 1.27 1.27) (thickness 0.15)) (justify left bottom) hide)
    )
    (pin "1")
  )

  (symbol (lib_id "sa800u-baseboard-hw:GND") (at 271.78 195.326 0) (unit 1)
    (in_bom yes) (on_board yes) (fields_autoplaced)
    (property "Reference" "#PWR0267" (id 0) (at 271.78 201.676 0)
      (effects (font (size 1.27 1.27)) hide)
    )
    (property "Value" "GND" (id 1) (at 271.78 200.406 0))
    (property "Footprint" "" (id 2) (at 271.78 195.326 0)
      (effects (font (size 1.27 1.27)) hide)
    )
    (property "Datasheet" "" (id 3) (at 271.78 195.326 0)
      (effects (font (size 1.27 1.27)) hide)
    )
    (property "Author" "Antmicro" (id 4) (at 280.67 202.946 0)
      (effects (font (size 1.27 1.27) (thickness 0.15)) (justify left bottom) hide)
    )
    (property "License" "Apache-2.0" (id 5) (at 280.67 205.486 0)
      (effects (font (size 1.27 1.27) (thickness 0.15)) (justify left bottom) hide)
    )
    (pin "1")
  )

  (symbol (lib_id "sa800u-baseboard-hw:R_4k7_0402") (at 276.225 64.008 90) (unit 1)
    (in_bom yes) (on_board yes)
    (property "Reference" "R172" (id 0) (at 276.606 58.42 90)
      (effects (font (size 1.524 1.524)) (justify right))
    )
    (property "Value" "R_4k7_0402" (id 1) (at 280.035 64.008 0)
      (effects (font (size 1.524 1.524)) hide)
    )
    (property "Footprint" "sa800u-baseboard-hw-footprints:R_0402_1005Metric" (id 2) (at 271.145 58.928 0)
      (effects (font (size 1.524 1.524)) (justify left) hide)
    )
    (property "Datasheet" "https://www.bourns.com/docs/product-datasheets/cr.pdf" (id 3) (at 276.225 64.008 0)
      (effects (font (size 1.27 1.27)) hide)
    )
    (property "Manufacturer" "Bourns" (id 4) (at 266.065 58.928 0)
      (effects (font (size 1.524 1.524)) (justify left) hide)
    )
    (property "MPN" "CR0402-FX-4701GLF" (id 5) (at 268.605 58.928 0)
      (effects (font (size 1.524 1.524)) (justify left) hide)
    )
    (property "Val" "4k7" (id 6) (at 277.368 61.468 90)
      (effects (font (size 1.27 1.27)) (justify right))
    )
    (property "License" "Apache-2.0" (id 7) (at 301.625 43.688 0)
      (effects (font (size 1.27 1.27) (thickness 0.15)) (justify left bottom) hide)
    )
    (property "Author" "Antmicro" (id 8) (at 304.165 43.688 0)
      (effects (font (size 1.27 1.27) (thickness 0.15)) (justify left bottom) hide)
    )
    (property "Tolerance" "1%" (id 9) (at 286.385 43.688 0)
      (effects (font (size 1.27 1.27)) (justify left bottom) hide)
    )
    (pin "1")
    (pin "2")
  )

  (symbol (lib_id "sa800u-baseboard-hw:GND") (at 182.88 135.255 0) (unit 1)
    (in_bom yes) (on_board yes) (fields_autoplaced)
    (property "Reference" "#PWR0259" (id 0) (at 182.88 141.605 0)
      (effects (font (size 1.27 1.27)) hide)
    )
    (property "Value" "GND" (id 1) (at 182.88 139.7 0))
    (property "Footprint" "" (id 2) (at 182.88 135.255 0)
      (effects (font (size 1.27 1.27)) hide)
    )
    (property "Datasheet" "" (id 3) (at 182.88 135.255 0)
      (effects (font (size 1.27 1.27)) hide)
    )
    (property "Author" "Antmicro" (id 4) (at 191.77 142.875 0)
      (effects (font (size 1.27 1.27) (thickness 0.15)) (justify left bottom) hide)
    )
    (property "License" "Apache-2.0" (id 5) (at 191.77 145.415 0)
      (effects (font (size 1.27 1.27) (thickness 0.15)) (justify left bottom) hide)
    )
    (pin "1")
  )

  (symbol (lib_id "sa800u-baseboard-hw:R_510R_0402") (at 276.86 156.337 90) (unit 1)
    (in_bom yes) (on_board yes)
    (property "Reference" "R171" (id 0) (at 269.367 152.5271 90)
      (effects (font (size 1.524 1.524)) (justify right))
    )
    (property "Value" "R_510R_0402" (id 1) (at 280.67 156.337 0)
      (effects (font (size 1.524 1.524)) hide)
    )
    (property "Footprint" "sa800u-baseboard-hw-footprints:R_0402_1005Metric" (id 2) (at 271.78 151.257 0)
      (effects (font (size 1.524 1.524)) (justify left) hide)
    )
    (property "Datasheet" "https://www.bourns.com/docs/product-datasheets/cr.pdf" (id 3) (at 276.86 156.337 0)
      (effects (font (size 1.27 1.27)) hide)
    )
    (property "Manufacturer" "Bourns" (id 4) (at 266.7 151.257 0)
      (effects (font (size 1.524 1.524)) (justify left) hide)
    )
    (property "MPN" "CR0402-FX-5100GLF" (id 5) (at 269.24 151.257 0)
      (effects (font (size 1.524 1.524)) (justify left) hide)
    )
    (property "Val" "510R" (id 6) (at 269.367 155.702 90)
      (effects (font (size 1.27 1.27)) (justify right))
    )
    (property "License" "Apache-2.0" (id 7) (at 302.26 136.017 0)
      (effects (font (size 1.27 1.27) (thickness 0.15)) (justify left bottom) hide)
    )
    (property "Author" "Antmicro" (id 8) (at 304.8 136.017 0)
      (effects (font (size 1.27 1.27) (thickness 0.15)) (justify left bottom) hide)
    )
    (property "Tolerance" "1%" (id 9) (at 287.02 136.017 0)
      (effects (font (size 1.27 1.27)) (justify left bottom) hide)
    )
    (pin "1")
    (pin "2")
  )

  (symbol (lib_id "sa800u-baseboard-hw:R_750R_0402") (at 281.94 151.257 270) (unit 1)
    (in_bom yes) (on_board yes)
    (property "Reference" "R173" (id 0) (at 280.162 148.59 90)
      (effects (font (size 1.524 1.524)) (justify left))
    )
    (property "Value" "R_750R_0402" (id 1) (at 278.13 151.257 0)
      (effects (font (size 1.524 1.524)) hide)
    )
    (property "Footprint" "sa800u-baseboard-hw-footprints:R_0402_1005Metric" (id 2) (at 287.02 156.337 0)
      (effects (font (size 1.524 1.524)) (justify left) hide)
    )
    (property "Datasheet" "https://www.bourns.com/docs/product-datasheets/cr.pdf" (id 3) (at 281.94 151.257 0)
      (effects (font (size 1.27 1.27)) hide)
    )
    (property "Manufacturer" "Bourns" (id 4) (at 292.1 156.337 0)
      (effects (font (size 1.524 1.524)) (justify left) hide)
    )
    (property "MPN" "CR0402-FX-7500GLF" (id 5) (at 289.56 156.337 0)
      (effects (font (size 1.524 1.524)) (justify left) hide)
    )
    (property "Val" "750R" (id 6) (at 281.94 157.099 90)
      (effects (font (size 1.27 1.27)) (justify left))
    )
    (property "License" "Apache-2.0" (id 7) (at 256.54 171.577 0)
      (effects (font (size 1.27 1.27) (thickness 0.15)) (justify left bottom) hide)
    )
    (property "Author" "Antmicro" (id 8) (at 254 171.577 0)
      (effects (font (size 1.27 1.27) (thickness 0.15)) (justify left bottom) hide)
    )
    (property "Tolerance" "1%" (id 9) (at 271.78 171.577 0)
      (effects (font (size 1.27 1.27)) (justify left bottom) hide)
    )
    (pin "1")
    (pin "2")
  )

  (symbol (lib_id "sa800u-baseboard-hw:R_2k7_0402") (at 287.02 151.13 270) (unit 1)
    (in_bom yes) (on_board yes) (fields_autoplaced)
    (property "Reference" "R174" (id 0) (at 289.56 152.4 90)
      (effects (font (size 1.524 1.524)) (justify left))
    )
    (property "Value" "R_2k7_0402" (id 1) (at 283.21 151.13 0)
      (effects (font (size 1.524 1.524)) hide)
    )
    (property "Footprint" "sa800u-baseboard-hw-footprints:R_0402_1005Metric" (id 2) (at 292.1 156.21 0)
      (effects (font (size 1.524 1.524)) (justify left) hide)
    )
    (property "Datasheet" "https://www.bourns.com/docs/product-datasheets/cr.pdf" (id 3) (at 287.02 151.13 0)
      (effects (font (size 1.27 1.27)) hide)
    )
    (property "Manufacturer" "Bourns" (id 4) (at 297.18 156.21 0)
      (effects (font (size 1.524 1.524)) (justify left) hide)
    )
    (property "MPN" "CR0402-FX-2701GLF" (id 5) (at 294.64 156.21 0)
      (effects (font (size 1.524 1.524)) (justify left) hide)
    )
    (property "Val" "2k7" (id 6) (at 289.56 155.5749 90)
      (effects (font (size 1.27 1.27)) (justify left))
    )
    (property "License" "Apache-2.0" (id 7) (at 261.62 171.45 0)
      (effects (font (size 1.27 1.27) (thickness 0.15)) (justify left bottom) hide)
    )
    (property "Author" "Antmicro" (id 8) (at 259.08 171.45 0)
      (effects (font (size 1.27 1.27) (thickness 0.15)) (justify left bottom) hide)
    )
    (property "Tolerance" "1%" (id 9) (at 276.86 171.45 0)
      (effects (font (size 1.27 1.27)) (justify left bottom) hide)
    )
    (pin "1")
    (pin "2")
  )

  (symbol (lib_id "sa800u-baseboard-hw:TP_0.75mm_SMD") (at 400.685 247.015 90) (unit 1)
    (in_bom yes) (on_board yes) (fields_autoplaced)
    (property "Reference" "TP98" (id 0) (at 402.59 243.8399 90)
      (effects (font (size 1.27 1.27)) (justify right))
    )
    (property "Value" "TP_0.75mm_SMD" (id 1) (at 400.685 247.015 0)
      (effects (font (size 1.27 1.27)) hide)
    )
    (property "Footprint" "sa800u-baseboard-hw-footprints:TP_SMD_0.75mm" (id 2) (at 400.685 247.015 0)
      (effects (font (size 1.27 1.27)) hide)
    )
    (property "Datasheet" "" (id 3) (at 400.685 247.015 0)
      (effects (font (size 1.27 1.27)) hide)
    )
    (property "MPN" "" (id 4) (at 415.925 229.235 0)
      (effects (font (size 1.27 1.27) (thickness 0.15)) (justify left bottom) hide)
    )
    (property "Manufacturer" "" (id 5) (at 418.465 229.235 0)
      (effects (font (size 1.27 1.27) (thickness 0.15)) (justify left bottom) hide)
    )
    (property "Author" "Antmicro" (id 6) (at 421.005 229.235 0)
      (effects (font (size 1.27 1.27) (thickness 0.15)) (justify left bottom) hide)
    )
    (property "License" "Apache-2.0" (id 7) (at 423.545 229.235 0)
      (effects (font (size 1.27 1.27) (thickness 0.15)) (justify left bottom) hide)
    )
    (pin "1")
  )

  (symbol (lib_id "sa800u-baseboard-hw:GND") (at 400.685 247.015 0) (unit 1)
    (in_bom yes) (on_board yes)
    (property "Reference" "#PWR0270" (id 0) (at 400.685 253.365 0)
      (effects (font (size 1.27 1.27)) hide)
    )
    (property "Value" "GND" (id 1) (at 400.812 251.4092 0))
    (property "Footprint" "" (id 2) (at 400.685 247.015 0)
      (effects (font (size 1.27 1.27)) hide)
    )
    (property "Datasheet" "" (id 3) (at 400.685 247.015 0)
      (effects (font (size 1.27 1.27)) hide)
    )
    (property "Author" "Antmicro" (id 4) (at 409.575 254.635 0)
      (effects (font (size 1.27 1.27) (thickness 0.15)) (justify left bottom) hide)
    )
    (property "License" "Apache-2.0" (id 5) (at 409.575 257.175 0)
      (effects (font (size 1.27 1.27) (thickness 0.15)) (justify left bottom) hide)
    )
    (pin "1")
  )

  (symbol (lib_id "sa800u-baseboard-hw:TP_0.75mm_SMD") (at 180.594 167.894 90) (unit 1)
    (in_bom yes) (on_board yes) (fields_autoplaced)
    (property "Reference" "TP88" (id 0) (at 183.007 164.7189 90)
      (effects (font (size 1.27 1.27)) (justify right))
    )
    (property "Value" "TP_0.75mm_SMD" (id 1) (at 183.134 167.894 0)
      (effects (font (size 1.27 1.27)) hide)
    )
    (property "Footprint" "sa800u-baseboard-hw-footprints:TP_SMD_0.75mm" (id 2) (at 175.514 162.814 0)
      (effects (font (size 1.524 1.524)) (justify left) hide)
    )
    (property "Datasheet" "" (id 3) (at 172.974 162.814 0)
      (effects (font (size 1.524 1.524)) (justify left) hide)
    )
    (property "MPN" "" (id 4) (at 195.834 150.114 0)
      (effects (font (size 1.27 1.27) (thickness 0.15)) (justify left bottom) hide)
    )
    (property "Manufacturer" "" (id 5) (at 198.374 150.114 0)
      (effects (font (size 1.27 1.27) (thickness 0.15)) (justify left bottom) hide)
    )
    (property "Author" "Antmicro" (id 6) (at 200.914 150.114 0)
      (effects (font (size 1.27 1.27) (thickness 0.15)) (justify left bottom) hide)
    )
    (property "License" "Apache-2.0" (id 7) (at 203.454 150.114 0)
      (effects (font (size 1.27 1.27) (thickness 0.15)) (justify left bottom) hide)
    )
    (pin "1")
  )

  (symbol (lib_id "sa800u-baseboard-hw:TP_0.75mm_SMD") (at 272.796 181.356 0) (unit 1)
    (in_bom yes) (on_board yes) (fields_autoplaced)
    (property "Reference" "TP97" (id 0) (at 278.257 181.3559 0)
      (effects (font (size 1.27 1.27)) (justify left))
    )
    (property "Value" "TP_0.75mm_SMD" (id 1) (at 272.796 183.896 0)
      (effects (font (size 1.27 1.27)) hide)
    )
    (property "Footprint" "sa800u-baseboard-hw-footprints:TP_SMD_0.75mm" (id 2) (at 277.876 176.276 0)
      (effects (font (size 1.524 1.524)) (justify left) hide)
    )
    (property "Datasheet" "" (id 3) (at 277.876 173.736 0)
      (effects (font (size 1.524 1.524)) (justify left) hide)
    )
    (property "MPN" "" (id 4) (at 290.576 196.596 0)
      (effects (font (size 1.27 1.27) (thickness 0.15)) (justify left bottom) hide)
    )
    (property "Manufacturer" "" (id 5) (at 290.576 199.136 0)
      (effects (font (size 1.27 1.27) (thickness 0.15)) (justify left bottom) hide)
    )
    (property "Author" "Antmicro" (id 6) (at 290.576 201.676 0)
      (effects (font (size 1.27 1.27) (thickness 0.15)) (justify left bottom) hide)
    )
    (property "License" "Apache-2.0" (id 7) (at 290.576 204.216 0)
      (effects (font (size 1.27 1.27) (thickness 0.15)) (justify left bottom) hide)
    )
    (pin "1")
  )

  (symbol (lib_id "sa800u-baseboard-hw:TP_0.75mm_SMD") (at 260.858 183.896 0) (unit 1)
    (in_bom yes) (on_board yes) (fields_autoplaced)
    (property "Reference" "TP92" (id 0) (at 266.319 183.8959 0)
      (effects (font (size 1.27 1.27)) (justify left))
    )
    (property "Value" "TP_0.75mm_SMD" (id 1) (at 260.858 186.436 0)
      (effects (font (size 1.27 1.27)) hide)
    )
    (property "Footprint" "sa800u-baseboard-hw-footprints:TP_SMD_0.75mm" (id 2) (at 265.938 178.816 0)
      (effects (font (size 1.524 1.524)) (justify left) hide)
    )
    (property "Datasheet" "" (id 3) (at 265.938 176.276 0)
      (effects (font (size 1.524 1.524)) (justify left) hide)
    )
    (property "MPN" "" (id 4) (at 278.638 199.136 0)
      (effects (font (size 1.27 1.27) (thickness 0.15)) (justify left bottom) hide)
    )
    (property "Manufacturer" "" (id 5) (at 278.638 201.676 0)
      (effects (font (size 1.27 1.27) (thickness 0.15)) (justify left bottom) hide)
    )
    (property "Author" "Antmicro" (id 6) (at 278.638 204.216 0)
      (effects (font (size 1.27 1.27) (thickness 0.15)) (justify left bottom) hide)
    )
    (property "License" "Apache-2.0" (id 7) (at 278.638 206.756 0)
      (effects (font (size 1.27 1.27) (thickness 0.15)) (justify left bottom) hide)
    )
    (pin "1")
  )

  (symbol (lib_id "sa800u-baseboard-hw:TP_0.75mm_SMD") (at 249.555 186.436 0) (unit 1)
    (in_bom yes) (on_board yes) (fields_autoplaced)
    (property "Reference" "TP90" (id 0) (at 255.016 186.4359 0)
      (effects (font (size 1.27 1.27)) (justify left))
    )
    (property "Value" "TP_0.75mm_SMD" (id 1) (at 249.555 188.976 0)
      (effects (font (size 1.27 1.27)) hide)
    )
    (property "Footprint" "sa800u-baseboard-hw-footprints:TP_SMD_0.75mm" (id 2) (at 254.635 181.356 0)
      (effects (font (size 1.524 1.524)) (justify left) hide)
    )
    (property "Datasheet" "" (id 3) (at 254.635 178.816 0)
      (effects (font (size 1.524 1.524)) (justify left) hide)
    )
    (property "MPN" "" (id 4) (at 267.335 201.676 0)
      (effects (font (size 1.27 1.27) (thickness 0.15)) (justify left bottom) hide)
    )
    (property "Manufacturer" "" (id 5) (at 267.335 204.216 0)
      (effects (font (size 1.27 1.27) (thickness 0.15)) (justify left bottom) hide)
    )
    (property "Author" "Antmicro" (id 6) (at 267.335 206.756 0)
      (effects (font (size 1.27 1.27) (thickness 0.15)) (justify left bottom) hide)
    )
    (property "License" "Apache-2.0" (id 7) (at 267.335 209.296 0)
      (effects (font (size 1.27 1.27) (thickness 0.15)) (justify left bottom) hide)
    )
    (pin "1")
  )

  (symbol (lib_id "sa800u-baseboard-hw:TP_0.75mm_SMD") (at 288.544 176.276 0) (unit 1)
    (in_bom yes) (on_board yes) (fields_autoplaced)
    (property "Reference" "TP94" (id 0) (at 294.132 176.2759 0)
      (effects (font (size 1.27 1.27)) (justify left))
    )
    (property "Value" "TP_0.75mm_SMD" (id 1) (at 288.544 178.816 0)
      (effects (font (size 1.27 1.27)) hide)
    )
    (property "Footprint" "sa800u-baseboard-hw-footprints:TP_SMD_0.75mm" (id 2) (at 293.624 171.196 0)
      (effects (font (size 1.524 1.524)) (justify left) hide)
    )
    (property "Datasheet" "" (id 3) (at 293.624 168.656 0)
      (effects (font (size 1.524 1.524)) (justify left) hide)
    )
    (property "MPN" "" (id 4) (at 306.324 191.516 0)
      (effects (font (size 1.27 1.27) (thickness 0.15)) (justify left bottom) hide)
    )
    (property "Manufacturer" "" (id 5) (at 306.324 194.056 0)
      (effects (font (size 1.27 1.27) (thickness 0.15)) (justify left bottom) hide)
    )
    (property "Author" "Antmicro" (id 6) (at 306.324 196.596 0)
      (effects (font (size 1.27 1.27) (thickness 0.15)) (justify left bottom) hide)
    )
    (property "License" "Apache-2.0" (id 7) (at 306.324 199.136 0)
      (effects (font (size 1.27 1.27) (thickness 0.15)) (justify left bottom) hide)
    )
    (pin "1")
  )

  (symbol (lib_id "sa800u-baseboard-hw:TP_0.75mm_SMD") (at 288.544 173.736 0) (unit 1)
    (in_bom yes) (on_board yes) (fields_autoplaced)
    (property "Reference" "TP93" (id 0) (at 293.116 173.7359 0)
      (effects (font (size 1.27 1.27)) (justify left))
    )
    (property "Value" "TP_0.75mm_SMD" (id 1) (at 288.544 176.276 0)
      (effects (font (size 1.27 1.27)) hide)
    )
    (property "Footprint" "sa800u-baseboard-hw-footprints:TP_SMD_0.75mm" (id 2) (at 293.624 168.656 0)
      (effects (font (size 1.524 1.524)) (justify left) hide)
    )
    (property "Datasheet" "" (id 3) (at 293.624 166.116 0)
      (effects (font (size 1.524 1.524)) (justify left) hide)
    )
    (property "MPN" "" (id 4) (at 306.324 188.976 0)
      (effects (font (size 1.27 1.27) (thickness 0.15)) (justify left bottom) hide)
    )
    (property "Manufacturer" "" (id 5) (at 306.324 191.516 0)
      (effects (font (size 1.27 1.27) (thickness 0.15)) (justify left bottom) hide)
    )
    (property "Author" "Antmicro" (id 6) (at 306.324 194.056 0)
      (effects (font (size 1.27 1.27) (thickness 0.15)) (justify left bottom) hide)
    )
    (property "License" "Apache-2.0" (id 7) (at 306.324 196.596 0)
      (effects (font (size 1.27 1.27) (thickness 0.15)) (justify left bottom) hide)
    )
    (pin "1")
  )

  (symbol (lib_id "sa800u-baseboard-hw:TP_0.75mm_SMD") (at 142.621 183.896 180) (unit 1)
    (in_bom yes) (on_board yes)
    (property "Reference" "TP86" (id 0) (at 135.128 184.023 0))
    (property "Value" "TP_0.75mm_SMD" (id 1) (at 142.621 181.356 0)
      (effects (font (size 1.27 1.27)) hide)
    )
    (property "Footprint" "sa800u-baseboard-hw-footprints:TP_SMD_0.75mm" (id 2) (at 137.541 188.976 0)
      (effects (font (size 1.524 1.524)) (justify left) hide)
    )
    (property "Datasheet" "" (id 3) (at 137.541 191.516 0)
      (effects (font (size 1.524 1.524)) (justify left) hide)
    )
    (property "MPN" "" (id 4) (at 124.841 168.656 0)
      (effects (font (size 1.27 1.27) (thickness 0.15)) (justify left bottom) hide)
    )
    (property "Manufacturer" "" (id 5) (at 124.841 166.116 0)
      (effects (font (size 1.27 1.27) (thickness 0.15)) (justify left bottom) hide)
    )
    (property "Author" "Antmicro" (id 6) (at 124.841 163.576 0)
      (effects (font (size 1.27 1.27) (thickness 0.15)) (justify left bottom) hide)
    )
    (property "License" "Apache-2.0" (id 7) (at 124.841 161.036 0)
      (effects (font (size 1.27 1.27) (thickness 0.15)) (justify left bottom) hide)
    )
    (pin "1")
  )

  (symbol (lib_id "sa800u-baseboard-hw:TP_0.75mm_SMD") (at 142.621 186.436 180) (unit 1)
    (in_bom yes) (on_board yes) (fields_autoplaced)
    (property "Reference" "TP87" (id 0) (at 137.541 186.4359 0)
      (effects (font (size 1.27 1.27)) (justify left))
    )
    (property "Value" "TP_0.75mm_SMD" (id 1) (at 142.621 183.896 0)
      (effects (font (size 1.27 1.27)) hide)
    )
    (property "Footprint" "sa800u-baseboard-hw-footprints:TP_SMD_0.75mm" (id 2) (at 137.541 191.516 0)
      (effects (font (size 1.524 1.524)) (justify left) hide)
    )
    (property "Datasheet" "" (id 3) (at 137.541 194.056 0)
      (effects (font (size 1.524 1.524)) (justify left) hide)
    )
    (property "MPN" "" (id 4) (at 124.841 171.196 0)
      (effects (font (size 1.27 1.27) (thickness 0.15)) (justify left bottom) hide)
    )
    (property "Manufacturer" "" (id 5) (at 124.841 168.656 0)
      (effects (font (size 1.27 1.27) (thickness 0.15)) (justify left bottom) hide)
    )
    (property "Author" "Antmicro" (id 6) (at 124.841 166.116 0)
      (effects (font (size 1.27 1.27) (thickness 0.15)) (justify left bottom) hide)
    )
    (property "License" "Apache-2.0" (id 7) (at 124.841 163.576 0)
      (effects (font (size 1.27 1.27) (thickness 0.15)) (justify left bottom) hide)
    )
    (pin "1")
  )

  (symbol (lib_id "sa800u-baseboard-hw:R_10k_0402") (at 178.816 172.466 270) (unit 1)
    (in_bom yes) (on_board yes) (fields_autoplaced)
    (property "Reference" "R153" (id 0) (at 180.721 173.736 90)
      (effects (font (size 1.524 1.524)) (justify left))
    )
    (property "Value" "R_10k_0402" (id 1) (at 175.006 172.466 0)
      (effects (font (size 1.524 1.524)) hide)
    )
    (property "Footprint" "sa800u-baseboard-hw-footprints:R_0402_1005Metric" (id 2) (at 183.896 177.546 0)
      (effects (font (size 1.524 1.524)) (justify left) hide)
    )
    (property "Datasheet" "https://www.bourns.com/docs/product-datasheets/cr.pdf" (id 3) (at 178.816 172.466 0)
      (effects (font (size 1.27 1.27)) hide)
    )
    (property "Manufacturer" "Bourns" (id 4) (at 188.976 177.546 0)
      (effects (font (size 1.524 1.524)) (justify left) hide)
    )
    (property "MPN" "CR0402-FX-1002GLF" (id 5) (at 186.436 177.546 0)
      (effects (font (size 1.524 1.524)) (justify left) hide)
    )
    (property "Val" "10k" (id 6) (at 180.721 176.9109 90)
      (effects (font (size 1.27 1.27)) (justify left))
    )
    (property "License" "Apache-2.0" (id 7) (at 153.416 192.786 0)
      (effects (font (size 1.27 1.27) (thickness 0.15)) (justify left bottom) hide)
    )
    (property "Author" "Antmicro" (id 8) (at 150.876 192.786 0)
      (effects (font (size 1.27 1.27) (thickness 0.15)) (justify left bottom) hide)
    )
    (property "Tolerance" "1%" (id 9) (at 168.656 192.786 0)
      (effects (font (size 1.27 1.27)) (justify left bottom) hide)
    )
    (pin "1")
    (pin "2")
  )

  (symbol (lib_id "sa800u-baseboard-hw:GND") (at 178.816 177.546 0) (unit 1)
    (in_bom yes) (on_board yes) (fields_autoplaced)
    (property "Reference" "#PWR0258" (id 0) (at 178.816 183.896 0)
      (effects (font (size 1.27 1.27)) hide)
    )
    (property "Value" "GND" (id 1) (at 178.816 182.626 0))
    (property "Footprint" "" (id 2) (at 178.816 177.546 0)
      (effects (font (size 1.27 1.27)) hide)
    )
    (property "Datasheet" "" (id 3) (at 178.816 177.546 0)
      (effects (font (size 1.27 1.27)) hide)
    )
    (property "Author" "Antmicro" (id 4) (at 187.706 185.166 0)
      (effects (font (size 1.27 1.27) (thickness 0.15)) (justify left bottom) hide)
    )
    (property "License" "Apache-2.0" (id 5) (at 187.706 187.706 0)
      (effects (font (size 1.27 1.27) (thickness 0.15)) (justify left bottom) hide)
    )
    (pin "1")
  )

  (symbol (lib_id "sa800u-baseboard-hw:PWR_FLAG") (at 271.78 181.356 0) (unit 1)
    (in_bom yes) (on_board yes)
    (property "Reference" "#FLG0106" (id 0) (at 271.78 179.451 0)
      (effects (font (size 1.27 1.27)) hide)
    )
    (property "Value" "PWR_FLAG" (id 1) (at 271.78 177.8 0))
    (property "Footprint" "" (id 2) (at 271.78 181.356 0)
      (effects (font (size 1.27 1.27)) hide)
    )
    (property "Datasheet" "~" (id 3) (at 271.78 181.356 0)
      (effects (font (size 1.27 1.27)) hide)
    )
    (pin "1")
  )
)
